FILE_TYPE = MACRO_DRAWING;
SET COLOR_WIRE YELLOW;
SET COLOR_PROP ORANGE;
SET COLOR_DOT WHITE;
SET COLOR_ARC YELLOW;
SET COLOR_BODY GREEN;
SET COLOR_NOTE PURPLE;
SET PROP_DISPLAY VALUE;
SET PAGE_NUMBER P99;
FORCEADD UNIVERSAL_GND..1
(-1650 -575);
FORCEPROP 3 LASTPIN (-1650 -525) SIG_NAME GND\g
J 0
(-1640 -515);
DISPLAY 0.659574 (-1640 -515);
PAINT MONO (-1640 -515);
DISPLAY INVISIBLE (-1640 -515);
FORCEPROP 1 LAST PATH I1
J 0
(-1575 -575);
DISPLAY 0.872340 (-1575 -575);
PAINT AQUA (-1575 -575);
DISPLAY INVISIBLE (-1575 -575);
FORCEPROP 1 LAST HDL_POWER GND
J 1
(-1625 -650);
DISPLAY 0.872340 (-1625 -650);
PAINT GREEN (-1625 -650);
DISPLAY INVISIBLE (-1625 -650);
FORCEPROP 2 LAST CDS_LIB logical_power
J 0
(-1650 -575);
PAINT MONO (-1650 -575);
DISPLAY INVISIBLE (-1650 -575);
FORCEADD OFFPAGE..1
(-2800 1550);
FORCEPROP 2 LAST $XR3 101 
J 0
(-3172 1514);
DISPLAY 0.638298 (-3172 1514);
PAINT MONO (-3172 1514);
FORCEPROP 2 LAST $XR2 100 
J 0
(-3052 1514);
DISPLAY 0.638298 (-3052 1514);
PAINT MONO (-3052 1514);
FORCEPROP 2 LAST $XR1 98 
J 0
(-3142 1550);
DISPLAY 0.638298 (-3142 1550);
PAINT MONO (-3142 1550);
FORCEPROP 2 LAST $XR0 130 
J 0
(-3052 1550);
DISPLAY 0.638298 (-3052 1550);
PAINT MONO (-3052 1550);
FORCEPROP 2 LAST CDS_LIB standard
J 0
(-2800 1550);
PAINT MONO (-2800 1550);
DISPLAY INVISIBLE (-2800 1550);
FORCEPROP 1 LAST OFFPAGE TRUE
J 0
(-2475 1425);
DISPLAY 0.872340 (-2475 1425);
DISPLAY INVISIBLE (-2475 1425);
FORCEPROP 1 LAST COMMENT_BODY TRUE
J 0
(-2675 1450);
DISPLAY 0.872340 (-2675 1450);
PAINT GREEN (-2675 1450);
DISPLAY INVISIBLE (-2675 1450);
FORCEPROP 2 LAST PATH I10
J 0
(-2750 1625);
DISPLAY 1.021277 (-2750 1625);
DISPLAY INVISIBLE (-2750 1625);
FORCEADD TAP..1
(-225 3050);
FORCEPROP 3 LASTPIN (-275 3050) SIG_NAME M_A_CPU1_SA_DQ<16>
J 0
(-265 3060);
DISPLAY 0.659574 (-265 3060);
PAINT MONO (-265 3060);
DISPLAY INVISIBLE (-265 3060);
FORCEPROP 1 LASTPIN (-275 3050) BN 16
J 0
(-287 3058);
DISPLAY 0.680851 (-287 3058);
PAINT GREEN (-287 3058);
FORCEPROP 2 LAST CDS_LIB standard
J 0
(-225 3050);
PAINT MONO (-225 3050);
DISPLAY INVISIBLE (-225 3050);
FORCEPROP 1 LAST BODY_TYPE PLUMBING
J 0
(-225 3100);
DISPLAY 0.872340 (-225 3100);
PAINT GREEN (-225 3100);
DISPLAY INVISIBLE (-225 3100);
FORCEPROP 1 LAST HDL_TAP TRUE
J 0
(100 2925);
DISPLAY 0.872340 (100 2925);
DISPLAY INVISIBLE (100 2925);
FORCEPROP 1 LAST PATH I100
J 0
(-227 3050);
DISPLAY 0.872340 (-227 3050);
PAINT GREEN (-227 3050);
DISPLAY INVISIBLE (-227 3050);
FORCEADD TAP..1
(-225 3150);
FORCEPROP 3 LASTPIN (-275 3150) SIG_NAME M_A_CPU1_SA_DQ<18>
J 0
(-265 3160);
DISPLAY 0.659574 (-265 3160);
PAINT MONO (-265 3160);
DISPLAY INVISIBLE (-265 3160);
FORCEPROP 1 LASTPIN (-275 3150) BN 18
J 0
(-287 3158);
DISPLAY 0.680851 (-287 3158);
PAINT GREEN (-287 3158);
FORCEPROP 2 LAST CDS_LIB standard
J 0
(-225 3150);
PAINT MONO (-225 3150);
DISPLAY INVISIBLE (-225 3150);
FORCEPROP 1 LAST BODY_TYPE PLUMBING
J 0
(-225 3200);
DISPLAY 0.872340 (-225 3200);
PAINT GREEN (-225 3200);
DISPLAY INVISIBLE (-225 3200);
FORCEPROP 1 LAST HDL_TAP TRUE
J 0
(100 3025);
DISPLAY 0.872340 (100 3025);
DISPLAY INVISIBLE (100 3025);
FORCEPROP 1 LAST PATH I101
J 0
(-227 3150);
DISPLAY 0.872340 (-227 3150);
PAINT GREEN (-227 3150);
DISPLAY INVISIBLE (-227 3150);
FORCEADD TAP..1
(-225 3100);
FORCEPROP 3 LASTPIN (-275 3100) SIG_NAME M_A_CPU1_SA_DQ<17>
J 0
(-265 3110);
DISPLAY 0.659574 (-265 3110);
PAINT MONO (-265 3110);
DISPLAY INVISIBLE (-265 3110);
FORCEPROP 1 LASTPIN (-275 3100) BN 17
J 0
(-287 3108);
DISPLAY 0.680851 (-287 3108);
PAINT GREEN (-287 3108);
FORCEPROP 2 LAST CDS_LIB standard
J 0
(-225 3100);
PAINT MONO (-225 3100);
DISPLAY INVISIBLE (-225 3100);
FORCEPROP 1 LAST BODY_TYPE PLUMBING
J 0
(-225 3150);
DISPLAY 0.872340 (-225 3150);
PAINT GREEN (-225 3150);
DISPLAY INVISIBLE (-225 3150);
FORCEPROP 1 LAST HDL_TAP TRUE
J 0
(100 2975);
DISPLAY 0.872340 (100 2975);
DISPLAY INVISIBLE (100 2975);
FORCEPROP 1 LAST PATH I102
J 0
(-227 3100);
DISPLAY 0.872340 (-227 3100);
PAINT GREEN (-227 3100);
DISPLAY INVISIBLE (-227 3100);
FORCEADD TAP..1
(-225 3200);
FORCEPROP 3 LASTPIN (-275 3200) SIG_NAME M_A_CPU1_SA_DQ<19>
J 0
(-265 3210);
DISPLAY 0.659574 (-265 3210);
PAINT MONO (-265 3210);
DISPLAY INVISIBLE (-265 3210);
FORCEPROP 1 LASTPIN (-275 3200) BN 19
J 0
(-287 3208);
DISPLAY 0.680851 (-287 3208);
PAINT GREEN (-287 3208);
FORCEPROP 2 LAST CDS_LIB standard
J 0
(-225 3200);
PAINT MONO (-225 3200);
DISPLAY INVISIBLE (-225 3200);
FORCEPROP 1 LAST BODY_TYPE PLUMBING
J 0
(-225 3250);
DISPLAY 0.872340 (-225 3250);
PAINT GREEN (-225 3250);
DISPLAY INVISIBLE (-225 3250);
FORCEPROP 1 LAST HDL_TAP TRUE
J 0
(100 3075);
DISPLAY 0.872340 (100 3075);
DISPLAY INVISIBLE (100 3075);
FORCEPROP 1 LAST PATH I103
J 0
(-227 3200);
DISPLAY 0.872340 (-227 3200);
PAINT GREEN (-227 3200);
DISPLAY INVISIBLE (-227 3200);
FORCEADD TAP..1
(-225 3300);
FORCEPROP 3 LASTPIN (-275 3300) SIG_NAME M_A_CPU1_SA_DQ<21>
J 0
(-265 3310);
DISPLAY 0.659574 (-265 3310);
PAINT MONO (-265 3310);
DISPLAY INVISIBLE (-265 3310);
FORCEPROP 1 LASTPIN (-275 3300) BN 21
J 0
(-287 3308);
DISPLAY 0.680851 (-287 3308);
PAINT GREEN (-287 3308);
FORCEPROP 2 LAST CDS_LIB standard
J 0
(-225 3300);
PAINT MONO (-225 3300);
DISPLAY INVISIBLE (-225 3300);
FORCEPROP 1 LAST BODY_TYPE PLUMBING
J 0
(-225 3350);
DISPLAY 0.872340 (-225 3350);
PAINT GREEN (-225 3350);
DISPLAY INVISIBLE (-225 3350);
FORCEPROP 1 LAST HDL_TAP TRUE
J 0
(100 3175);
DISPLAY 0.872340 (100 3175);
DISPLAY INVISIBLE (100 3175);
FORCEPROP 1 LAST PATH I104
J 0
(-227 3300);
DISPLAY 0.872340 (-227 3300);
PAINT GREEN (-227 3300);
DISPLAY INVISIBLE (-227 3300);
FORCEADD TAP..1
(-225 3250);
FORCEPROP 3 LASTPIN (-275 3250) SIG_NAME M_A_CPU1_SA_DQ<20>
J 0
(-265 3260);
DISPLAY 0.659574 (-265 3260);
PAINT MONO (-265 3260);
DISPLAY INVISIBLE (-265 3260);
FORCEPROP 1 LASTPIN (-275 3250) BN 20
J 0
(-287 3258);
DISPLAY 0.680851 (-287 3258);
PAINT GREEN (-287 3258);
FORCEPROP 2 LAST CDS_LIB standard
J 0
(-225 3250);
PAINT MONO (-225 3250);
DISPLAY INVISIBLE (-225 3250);
FORCEPROP 1 LAST BODY_TYPE PLUMBING
J 0
(-225 3300);
DISPLAY 0.872340 (-225 3300);
PAINT GREEN (-225 3300);
DISPLAY INVISIBLE (-225 3300);
FORCEPROP 1 LAST HDL_TAP TRUE
J 0
(100 3125);
DISPLAY 0.872340 (100 3125);
DISPLAY INVISIBLE (100 3125);
FORCEPROP 1 LAST PATH I105
J 0
(-227 3250);
DISPLAY 0.872340 (-227 3250);
PAINT GREEN (-227 3250);
DISPLAY INVISIBLE (-227 3250);
FORCEADD TAP..1
(-225 3400);
FORCEPROP 3 LASTPIN (-275 3400) SIG_NAME M_A_CPU1_SA_DQ<23>
J 0
(-265 3410);
DISPLAY 0.659574 (-265 3410);
PAINT MONO (-265 3410);
DISPLAY INVISIBLE (-265 3410);
FORCEPROP 1 LASTPIN (-275 3400) BN 23
J 0
(-287 3408);
DISPLAY 0.680851 (-287 3408);
PAINT GREEN (-287 3408);
FORCEPROP 2 LAST CDS_LIB standard
J 0
(-225 3400);
DISPLAY INVISIBLE (-225 3400);
FORCEPROP 1 LAST BODY_TYPE PLUMBING
J 0
(-225 3450);
DISPLAY 0.872340 (-225 3450);
PAINT GREEN (-225 3450);
DISPLAY INVISIBLE (-225 3450);
FORCEPROP 1 LAST HDL_TAP TRUE
J 0
(100 3275);
DISPLAY 0.872340 (100 3275);
DISPLAY INVISIBLE (100 3275);
FORCEPROP 1 LAST PATH I106
J 0
(-227 3400);
DISPLAY 0.872340 (-227 3400);
PAINT GREEN (-227 3400);
DISPLAY INVISIBLE (-227 3400);
FORCEADD TAP..1
(-225 3350);
FORCEPROP 3 LASTPIN (-275 3350) SIG_NAME M_A_CPU1_SA_DQ<22>
J 0
(-265 3360);
DISPLAY 0.659574 (-265 3360);
PAINT MONO (-265 3360);
DISPLAY INVISIBLE (-265 3360);
FORCEPROP 1 LASTPIN (-275 3350) BN 22
J 0
(-287 3358);
DISPLAY 0.680851 (-287 3358);
PAINT GREEN (-287 3358);
FORCEPROP 2 LAST CDS_LIB standard
J 0
(-225 3350);
DISPLAY INVISIBLE (-225 3350);
FORCEPROP 1 LAST BODY_TYPE PLUMBING
J 0
(-225 3400);
DISPLAY 0.872340 (-225 3400);
PAINT GREEN (-225 3400);
DISPLAY INVISIBLE (-225 3400);
FORCEPROP 1 LAST HDL_TAP TRUE
J 0
(100 3225);
DISPLAY 0.872340 (100 3225);
DISPLAY INVISIBLE (100 3225);
FORCEPROP 1 LAST PATH I107
J 0
(-227 3350);
DISPLAY 0.872340 (-227 3350);
PAINT GREEN (-227 3350);
DISPLAY INVISIBLE (-227 3350);
FORCEADD TAP..1
(-225 3500);
FORCEPROP 3 LASTPIN (-275 3500) SIG_NAME M_A_CPU1_SA_DQ<25>
J 0
(-265 3510);
DISPLAY 0.659574 (-265 3510);
PAINT MONO (-265 3510);
DISPLAY INVISIBLE (-265 3510);
FORCEPROP 1 LASTPIN (-275 3500) BN 25
J 0
(-287 3508);
DISPLAY 0.680851 (-287 3508);
PAINT GREEN (-287 3508);
FORCEPROP 2 LAST CDS_LIB standard
J 0
(-225 3500);
DISPLAY INVISIBLE (-225 3500);
FORCEPROP 1 LAST BODY_TYPE PLUMBING
J 0
(-225 3550);
DISPLAY 0.872340 (-225 3550);
PAINT GREEN (-225 3550);
DISPLAY INVISIBLE (-225 3550);
FORCEPROP 1 LAST HDL_TAP TRUE
J 0
(100 3375);
DISPLAY 0.872340 (100 3375);
DISPLAY INVISIBLE (100 3375);
FORCEPROP 1 LAST PATH I108
J 0
(-227 3500);
DISPLAY 0.872340 (-227 3500);
PAINT GREEN (-227 3500);
DISPLAY INVISIBLE (-227 3500);
FORCEADD TAP..1
(-225 3450);
FORCEPROP 3 LASTPIN (-275 3450) SIG_NAME M_A_CPU1_SA_DQ<24>
J 0
(-265 3460);
DISPLAY 0.659574 (-265 3460);
PAINT MONO (-265 3460);
DISPLAY INVISIBLE (-265 3460);
FORCEPROP 1 LASTPIN (-275 3450) BN 24
J 0
(-287 3458);
DISPLAY 0.680851 (-287 3458);
PAINT GREEN (-287 3458);
FORCEPROP 2 LAST CDS_LIB standard
J 0
(-225 3450);
DISPLAY INVISIBLE (-225 3450);
FORCEPROP 1 LAST BODY_TYPE PLUMBING
J 0
(-225 3500);
DISPLAY 0.872340 (-225 3500);
PAINT GREEN (-225 3500);
DISPLAY INVISIBLE (-225 3500);
FORCEPROP 1 LAST HDL_TAP TRUE
J 0
(100 3325);
DISPLAY 0.872340 (100 3325);
DISPLAY INVISIBLE (100 3325);
FORCEPROP 1 LAST PATH I109
J 0
(-227 3450);
DISPLAY 0.872340 (-227 3450);
PAINT GREEN (-227 3450);
DISPLAY INVISIBLE (-227 3450);
FORCEADD OFFPAGE..1
(-2800 1450);
FORCEPROP 2 LAST $XR1 98 
J 0
(-3111 1450);
DISPLAY 0.638298 (-3111 1450);
PAINT MONO (-3111 1450);
FORCEPROP 2 LAST $XR0 51 
J 0
(-3021 1450);
DISPLAY 0.638298 (-3021 1450);
PAINT MONO (-3021 1450);
FORCEPROP 2 LAST CDS_LIB standard
J 0
(-2800 1450);
PAINT MONO (-2800 1450);
DISPLAY INVISIBLE (-2800 1450);
FORCEPROP 1 LAST OFFPAGE TRUE
J 0
(-2475 1325);
DISPLAY 0.872340 (-2475 1325);
DISPLAY INVISIBLE (-2475 1325);
FORCEPROP 1 LAST COMMENT_BODY TRUE
J 0
(-2675 1350);
DISPLAY 0.872340 (-2675 1350);
PAINT GREEN (-2675 1350);
DISPLAY INVISIBLE (-2675 1350);
FORCEPROP 2 LAST PATH I11
J 0
(-2750 1525);
DISPLAY 1.021277 (-2750 1525);
DISPLAY INVISIBLE (-2750 1525);
FORCEADD TAP..1
(-225 3550);
FORCEPROP 3 LASTPIN (-275 3550) SIG_NAME M_A_CPU1_SA_DQ<26>
J 0
(-265 3560);
DISPLAY 0.659574 (-265 3560);
PAINT MONO (-265 3560);
DISPLAY INVISIBLE (-265 3560);
FORCEPROP 1 LASTPIN (-275 3550) BN 26
J 0
(-287 3558);
DISPLAY 0.680851 (-287 3558);
PAINT GREEN (-287 3558);
FORCEPROP 2 LAST CDS_LIB standard
J 0
(-225 3550);
DISPLAY INVISIBLE (-225 3550);
FORCEPROP 1 LAST BODY_TYPE PLUMBING
J 0
(-225 3600);
DISPLAY 0.872340 (-225 3600);
PAINT GREEN (-225 3600);
DISPLAY INVISIBLE (-225 3600);
FORCEPROP 1 LAST HDL_TAP TRUE
J 0
(100 3425);
DISPLAY 0.872340 (100 3425);
DISPLAY INVISIBLE (100 3425);
FORCEPROP 1 LAST PATH I110
J 0
(-227 3550);
DISPLAY 0.872340 (-227 3550);
PAINT GREEN (-227 3550);
DISPLAY INVISIBLE (-227 3550);
FORCEADD TAP..1
(-225 3600);
FORCEPROP 3 LASTPIN (-275 3600) SIG_NAME M_A_CPU1_SA_DQ<27>
J 0
(-265 3610);
DISPLAY 0.659574 (-265 3610);
PAINT MONO (-265 3610);
DISPLAY INVISIBLE (-265 3610);
FORCEPROP 1 LASTPIN (-275 3600) BN 27
J 0
(-287 3608);
DISPLAY 0.680851 (-287 3608);
PAINT GREEN (-287 3608);
FORCEPROP 2 LAST CDS_LIB standard
J 0
(-225 3600);
DISPLAY INVISIBLE (-225 3600);
FORCEPROP 1 LAST BODY_TYPE PLUMBING
J 0
(-225 3650);
DISPLAY 0.872340 (-225 3650);
PAINT GREEN (-225 3650);
DISPLAY INVISIBLE (-225 3650);
FORCEPROP 1 LAST HDL_TAP TRUE
J 0
(100 3475);
DISPLAY 0.872340 (100 3475);
DISPLAY INVISIBLE (100 3475);
FORCEPROP 1 LAST PATH I111
J 0
(-227 3600);
DISPLAY 0.872340 (-227 3600);
PAINT GREEN (-227 3600);
DISPLAY INVISIBLE (-227 3600);
FORCEADD TAP..1
(-225 3650);
FORCEPROP 3 LASTPIN (-275 3650) SIG_NAME M_A_CPU1_SA_DQ<28>
J 0
(-265 3660);
DISPLAY 0.659574 (-265 3660);
PAINT MONO (-265 3660);
DISPLAY INVISIBLE (-265 3660);
FORCEPROP 1 LASTPIN (-275 3650) BN 28
J 0
(-287 3658);
DISPLAY 0.680851 (-287 3658);
PAINT GREEN (-287 3658);
FORCEPROP 2 LAST CDS_LIB standard
J 0
(-225 3650);
DISPLAY INVISIBLE (-225 3650);
FORCEPROP 1 LAST BODY_TYPE PLUMBING
J 0
(-225 3700);
DISPLAY 0.872340 (-225 3700);
PAINT GREEN (-225 3700);
DISPLAY INVISIBLE (-225 3700);
FORCEPROP 1 LAST HDL_TAP TRUE
J 0
(100 3525);
DISPLAY 0.872340 (100 3525);
DISPLAY INVISIBLE (100 3525);
FORCEPROP 1 LAST PATH I112
J 0
(-227 3650);
DISPLAY 0.872340 (-227 3650);
PAINT GREEN (-227 3650);
DISPLAY INVISIBLE (-227 3650);
FORCEADD OFFPAGE..1
(-2800 3825);
FORCEPROP 2 LAST $XR1 98 
J 0
(-3111 3825);
DISPLAY 0.638298 (-3111 3825);
PAINT MONO (-3111 3825);
FORCEPROP 2 LAST $XR0 51 
J 0
(-3021 3825);
DISPLAY 0.638298 (-3021 3825);
PAINT MONO (-3021 3825);
FORCEPROP 2 LAST CDS_LIB standard
J 0
(-2800 3825);
PAINT MONO (-2800 3825);
DISPLAY INVISIBLE (-2800 3825);
FORCEPROP 1 LAST OFFPAGE TRUE
J 0
(-2475 3700);
DISPLAY 0.872340 (-2475 3700);
DISPLAY INVISIBLE (-2475 3700);
FORCEPROP 1 LAST COMMENT_BODY TRUE
J 0
(-2675 3725);
DISPLAY 0.872340 (-2675 3725);
PAINT GREEN (-2675 3725);
DISPLAY INVISIBLE (-2675 3725);
FORCEPROP 2 LAST PATH I113
J 0
(-2750 3900);
DISPLAY 1.021277 (-2750 3900);
DISPLAY INVISIBLE (-2750 3900);
FORCEADD TAP..1
R 2
(-1875 3750);
FORCEPROP 3 LASTPIN (-1825 3750) SIG_NAME M_A_CPU1_SA_CA<5>
J 0
(-1815 3760);
DISPLAY 0.659574 (-1815 3760);
PAINT MONO (-1815 3760);
DISPLAY INVISIBLE (-1815 3760);
FORCEPROP 1 LASTPIN (-1825 3750) BN 5
J 2
(-1813 3758);
DISPLAY 0.680851 (-1813 3758);
PAINT GREEN (-1813 3758);
FORCEPROP 2 LAST CDS_LIB standard
J 0
(-1875 3750);
DISPLAY INVISIBLE (-1875 3750);
FORCEPROP 1 LAST BODY_TYPE PLUMBING
J 2
(-1875 3800);
DISPLAY 0.872340 (-1875 3800);
PAINT GREEN (-1875 3800);
DISPLAY INVISIBLE (-1875 3800);
FORCEPROP 1 LAST HDL_TAP TRUE
J 2
(-2200 3625);
DISPLAY 0.872340 (-2200 3625);
DISPLAY INVISIBLE (-2200 3625);
FORCEPROP 1 LAST PATH I114
J 2
(-1873 3750);
DISPLAY 0.872340 (-1873 3750);
PAINT GREEN (-1873 3750);
DISPLAY INVISIBLE (-1873 3750);
FORCEADD TAP..1
R 2
(-1875 3700);
FORCEPROP 3 LASTPIN (-1825 3700) SIG_NAME M_A_CPU1_SA_CA<4>
J 0
(-1815 3710);
DISPLAY 0.659574 (-1815 3710);
PAINT MONO (-1815 3710);
DISPLAY INVISIBLE (-1815 3710);
FORCEPROP 1 LASTPIN (-1825 3700) BN 4
J 2
(-1813 3708);
DISPLAY 0.680851 (-1813 3708);
PAINT GREEN (-1813 3708);
FORCEPROP 2 LAST CDS_LIB standard
J 0
(-1875 3700);
DISPLAY INVISIBLE (-1875 3700);
FORCEPROP 1 LAST BODY_TYPE PLUMBING
J 2
(-1875 3750);
DISPLAY 0.872340 (-1875 3750);
PAINT GREEN (-1875 3750);
DISPLAY INVISIBLE (-1875 3750);
FORCEPROP 1 LAST HDL_TAP TRUE
J 2
(-2200 3575);
DISPLAY 0.872340 (-2200 3575);
DISPLAY INVISIBLE (-2200 3575);
FORCEPROP 1 LAST PATH I115
J 2
(-1873 3700);
DISPLAY 0.872340 (-1873 3700);
PAINT GREEN (-1873 3700);
DISPLAY INVISIBLE (-1873 3700);
FORCEADD TAP..1
R 2
(-1875 3800);
FORCEPROP 3 LASTPIN (-1825 3800) SIG_NAME M_A_CPU1_SA_CA<6>
J 0
(-1815 3810);
DISPLAY 0.659574 (-1815 3810);
PAINT MONO (-1815 3810);
DISPLAY INVISIBLE (-1815 3810);
FORCEPROP 1 LASTPIN (-1825 3800) BN 6
J 2
(-1813 3808);
DISPLAY 0.680851 (-1813 3808);
PAINT GREEN (-1813 3808);
FORCEPROP 2 LAST CDS_LIB standard
J 0
(-1875 3800);
DISPLAY INVISIBLE (-1875 3800);
FORCEPROP 1 LAST BODY_TYPE PLUMBING
J 2
(-1875 3850);
DISPLAY 0.872340 (-1875 3850);
PAINT GREEN (-1875 3850);
DISPLAY INVISIBLE (-1875 3850);
FORCEPROP 1 LAST HDL_TAP TRUE
J 2
(-2200 3675);
DISPLAY 0.872340 (-2200 3675);
DISPLAY INVISIBLE (-2200 3675);
FORCEPROP 1 LAST PATH I116
J 2
(-1873 3800);
DISPLAY 0.872340 (-1873 3800);
PAINT GREEN (-1873 3800);
DISPLAY INVISIBLE (-1873 3800);
FORCEADD TAP..1
(-225 3700);
FORCEPROP 3 LASTPIN (-275 3700) SIG_NAME M_A_CPU1_SA_DQ<29>
J 0
(-265 3710);
DISPLAY 0.659574 (-265 3710);
PAINT MONO (-265 3710);
DISPLAY INVISIBLE (-265 3710);
FORCEPROP 1 LASTPIN (-275 3700) BN 29
J 0
(-287 3708);
DISPLAY 0.680851 (-287 3708);
PAINT GREEN (-287 3708);
FORCEPROP 2 LAST CDS_LIB standard
J 0
(-225 3700);
DISPLAY INVISIBLE (-225 3700);
FORCEPROP 1 LAST BODY_TYPE PLUMBING
J 0
(-225 3750);
DISPLAY 0.872340 (-225 3750);
PAINT GREEN (-225 3750);
DISPLAY INVISIBLE (-225 3750);
FORCEPROP 1 LAST HDL_TAP TRUE
J 0
(100 3575);
DISPLAY 0.872340 (100 3575);
DISPLAY INVISIBLE (100 3575);
FORCEPROP 1 LAST PATH I117
J 0
(-227 3700);
DISPLAY 0.872340 (-227 3700);
PAINT GREEN (-227 3700);
DISPLAY INVISIBLE (-227 3700);
FORCEADD TAP..1
(-225 3750);
FORCEPROP 3 LASTPIN (-275 3750) SIG_NAME M_A_CPU1_SA_DQ<30>
J 0
(-265 3760);
DISPLAY 0.659574 (-265 3760);
PAINT MONO (-265 3760);
DISPLAY INVISIBLE (-265 3760);
FORCEPROP 1 LASTPIN (-275 3750) BN 30
J 0
(-287 3758);
DISPLAY 0.680851 (-287 3758);
PAINT GREEN (-287 3758);
FORCEPROP 2 LAST CDS_LIB standard
J 0
(-225 3750);
DISPLAY INVISIBLE (-225 3750);
FORCEPROP 1 LAST BODY_TYPE PLUMBING
J 0
(-225 3800);
DISPLAY 0.872340 (-225 3800);
PAINT GREEN (-225 3800);
DISPLAY INVISIBLE (-225 3800);
FORCEPROP 1 LAST HDL_TAP TRUE
J 0
(100 3625);
DISPLAY 0.872340 (100 3625);
DISPLAY INVISIBLE (100 3625);
FORCEPROP 1 LAST PATH I118
J 0
(-227 3750);
DISPLAY 0.872340 (-227 3750);
PAINT GREEN (-227 3750);
DISPLAY INVISIBLE (-227 3750);
FORCEADD TAP..1
(-225 3800);
FORCEPROP 3 LASTPIN (-275 3800) SIG_NAME M_A_CPU1_SA_DQ<31>
J 0
(-265 3810);
DISPLAY 0.659574 (-265 3810);
PAINT MONO (-265 3810);
DISPLAY INVISIBLE (-265 3810);
FORCEPROP 1 LASTPIN (-275 3800) BN 31
J 0
(-287 3808);
DISPLAY 0.680851 (-287 3808);
PAINT GREEN (-287 3808);
FORCEPROP 2 LAST CDS_LIB standard
J 0
(-225 3800);
DISPLAY INVISIBLE (-225 3800);
FORCEPROP 1 LAST BODY_TYPE PLUMBING
J 0
(-225 3850);
DISPLAY 0.872340 (-225 3850);
PAINT GREEN (-225 3850);
DISPLAY INVISIBLE (-225 3850);
FORCEPROP 1 LAST HDL_TAP TRUE
J 0
(100 3675);
DISPLAY 0.872340 (100 3675);
DISPLAY INVISIBLE (100 3675);
FORCEPROP 1 LAST PATH I119
J 0
(-227 3800);
DISPLAY 0.872340 (-227 3800);
PAINT GREEN (-227 3800);
DISPLAY INVISIBLE (-227 3800);
FORCEADD VCC_CORE..1
(-2700 1675);
FORCEPROP 3 LASTPIN (-2700 1625) SIG_NAME P3V3_AUX\g
J 0
(-2690 1635);
DISPLAY 0.659574 (-2690 1635);
PAINT MONO (-2690 1635);
DISPLAY INVISIBLE (-2690 1635);
FORCEPROP 1 LAST HDL_POWER P3V3_AUX
J 1
(-2700 1725);
DISPLAY 1.148936 (-2700 1725);
PAINT GREEN (-2700 1725);
FORCEPROP 2 LAST CDS_LIB logical_power
J 0
(-2700 1675);
PAINT MONO (-2700 1675);
DISPLAY INVISIBLE (-2700 1675);
FORCEPROP 1 LAST PATH I12
J 0
(-2650 1700);
DISPLAY 0.872340 (-2650 1700);
PAINT AQUA (-2650 1700);
DISPLAY INVISIBLE (-2650 1700);
FORCEADD UNIVERSAL_GND..1
(1500 -450);
FORCEPROP 3 LASTPIN (1500 -400) SIG_NAME GND\g
J 0
(1510 -390);
DISPLAY 0.659574 (1510 -390);
PAINT MONO (1510 -390);
DISPLAY INVISIBLE (1510 -390);
FORCEPROP 1 LAST PATH I120
J 0
(1575 -450);
DISPLAY 0.872340 (1575 -450);
PAINT AQUA (1575 -450);
DISPLAY INVISIBLE (1575 -450);
FORCEPROP 1 LAST HDL_POWER GND
J 1
(1525 -525);
DISPLAY 0.872340 (1525 -525);
PAINT GREEN (1525 -525);
DISPLAY INVISIBLE (1525 -525);
FORCEPROP 2 LAST CDS_LIB logical_power
J 0
(1500 -450);
PAINT MONO (1500 -450);
DISPLAY INVISIBLE (1500 -450);
FORCEADD UNIVERSAL_GND..1
(3125 -450);
FORCEPROP 3 LASTPIN (3125 -400) SIG_NAME GND\g
J 0
(3135 -390);
DISPLAY 0.659574 (3135 -390);
PAINT MONO (3135 -390);
DISPLAY INVISIBLE (3135 -390);
FORCEPROP 1 LAST PATH I121
J 0
(3200 -450);
DISPLAY 0.872340 (3200 -450);
PAINT AQUA (3200 -450);
DISPLAY INVISIBLE (3200 -450);
FORCEPROP 1 LAST HDL_POWER GND
J 1
(3150 -525);
DISPLAY 0.872340 (3150 -525);
PAINT GREEN (3150 -525);
DISPLAY INVISIBLE (3150 -525);
FORCEPROP 2 LAST CDS_LIB logical_power
J 0
(3125 -450);
PAINT MONO (3125 -450);
DISPLAY INVISIBLE (3125 -450);
FORCEADD Q_CAP..1
(1500 -75);
FORCEPROP 1 LAST PART_NUMBER CH5221MEB00
J 0
(1550 -225);
DISPLAY 0.978723 (1550 -225);
DISPLAY INVISIBLE (1550 -225);
FORCEPROP 1 LAST VALUE 2.2UF
J 0
(1550 -25);
DISPLAY 0.978723 (1550 -25);
FORCEPROP 1 LAST TOLERANCE 20%
J 0
(1550 -125);
DISPLAY 0.978723 (1550 -125);
FORCEPROP 1 LAST MATERIAL X6S
J 0
(1550 -175);
DISPLAY 0.978723 (1550 -175);
FORCEPROP 1 LAST VOLTAGE 6.3V
J 0
(1550 -75);
DISPLAY 0.978723 (1550 -75);
FORCEPROP 1 LAST PACK_TYPE C0402
J 0
(1550 -275);
DISPLAY 0.978723 (1550 -275);
FORCEPROP 1 LAST $LOCATION C53
J 0
(1550 25);
DISPLAY 0.978723 (1550 25);
FORCEPROP 1 LASTPIN (1500 25) $PN 1
J 0
(1510 5);
DISPLAY 0.787234 (1510 5);
FORCEPROP 1 LASTPIN (1500 -175) $PN 2
J 0
(1510 -195);
DISPLAY 0.787234 (1510 -195);
FORCEPROP 2 LAST CDS_LIB pure_quanta
J 0
(1500 -75);
PAINT MONO (1500 -75);
DISPLAY INVISIBLE (1500 -75);
FORCEPROP 1 LAST PATH I122
J 0
(1550 75);
DISPLAY 0.978723 (1550 75);
PAINT WHITE (1550 75);
DISPLAY INVISIBLE (1550 75);
FORCEPROP 2 LAST CDS_LOCATION C53
J 0
(1550 125);
DISPLAY 1.021277 (1550 125);
DISPLAY INVISIBLE (1550 125);
FORCEPROP 2 LAST $SEC 1
J 0
(1550 125);
DISPLAY 0.680851 (1550 125);
PAINT MONO (1550 125);
DISPLAY INVISIBLE (1550 125);
FORCEPROP 2 LAST CDS_SEC 1
J 0
(1550 125);
DISPLAY 1.021277 (1550 125);
DISPLAY INVISIBLE (1550 125);
FORCEADD VCC_CORE..1
(1500 250);
FORCEPROP 3 LASTPIN (1500 200) SIG_NAME P3V3_AUX\g
J 0
(1510 210);
DISPLAY 0.659574 (1510 210);
PAINT MONO (1510 210);
DISPLAY INVISIBLE (1510 210);
FORCEPROP 1 LAST HDL_POWER P3V3_AUX
J 1
(1500 300);
DISPLAY 1.148936 (1500 300);
PAINT GREEN (1500 300);
FORCEPROP 2 LAST CDS_LIB logical_power
J 0
(1500 250);
PAINT MONO (1500 250);
DISPLAY INVISIBLE (1500 250);
FORCEPROP 1 LAST PATH I123
J 0
(1550 275);
DISPLAY 0.872340 (1550 275);
PAINT AQUA (1550 275);
DISPLAY INVISIBLE (1550 275);
FORCEADD OFFPAGE..3
(600 2175);
FORCEPROP 2 LAST $XR1 98 
J 0
(904 2175);
DISPLAY 0.638298 (904 2175);
PAINT MONO (904 2175);
FORCEPROP 2 LAST $XR0 51 
J 0
(814 2175);
DISPLAY 0.638298 (814 2175);
PAINT MONO (814 2175);
FORCEPROP 2 LAST CDS_LIB standard
J 2
(600 2175);
DISPLAY INVISIBLE (600 2175);
FORCEPROP 1 LAST OFFPAGE TRUE
J 0
(925 2050);
DISPLAY 0.872340 (925 2050);
DISPLAY INVISIBLE (925 2050);
FORCEPROP 1 LAST COMMENT_BODY TRUE
J 0
(550 2075);
DISPLAY 0.872340 (550 2075);
PAINT GREEN (550 2075);
DISPLAY INVISIBLE (550 2075);
FORCEPROP 2 LAST PATH I124
J 0
(800 2250);
DISPLAY 1.021277 (800 2250);
DISPLAY INVISIBLE (800 2250);
FORCEADD Q_CAP..1
(2500 -75);
FORCEPROP 1 LAST PART_NUMBER CH6103KEA00
J 0
(2550 -225);
DISPLAY 0.978723 (2550 -225);
DISPLAY INVISIBLE (2550 -225);
FORCEPROP 1 LAST VALUE 10UF
J 0
(2550 -25);
DISPLAY 0.978723 (2550 -25);
FORCEPROP 1 LAST PACK_TYPE C0805
J 0
(2550 -275);
DISPLAY 0.978723 (2550 -275);
FORCEPROP 1 LAST TOLERANCE 10%
J 0
(2550 -125);
DISPLAY 0.978723 (2550 -125);
FORCEPROP 1 LAST VOLTAGE 16V
J 0
(2550 -75);
DISPLAY 0.978723 (2550 -75);
FORCEPROP 1 LAST MATERIAL X6S
J 0
(2550 -175);
DISPLAY 0.978723 (2550 -175);
FORCEPROP 1 LAST $LOCATION C54
J 0
(2550 25);
DISPLAY 0.978723 (2550 25);
FORCEPROP 1 LASTPIN (2500 25) $PN 1
J 0
(2510 5);
DISPLAY 0.787234 (2510 5);
FORCEPROP 1 LASTPIN (2500 -175) $PN 2
J 0
(2510 -195);
DISPLAY 0.787234 (2510 -195);
FORCEPROP 2 LAST CDS_LIB pure_quanta
J 0
(2500 -75);
PAINT MONO (2500 -75);
DISPLAY INVISIBLE (2500 -75);
FORCEPROP 1 LAST PATH I126
J 0
(2550 75);
DISPLAY 0.978723 (2550 75);
PAINT WHITE (2550 75);
DISPLAY INVISIBLE (2550 75);
FORCEPROP 2 LAST CDS_LOCATION C54
J 0
(2550 125);
DISPLAY 1.021277 (2550 125);
DISPLAY INVISIBLE (2550 125);
FORCEPROP 2 LAST $SEC 1
J 0
(2550 125);
DISPLAY 0.680851 (2550 125);
PAINT MONO (2550 125);
DISPLAY INVISIBLE (2550 125);
FORCEPROP 2 LAST CDS_SEC 1
J 0
(2550 125);
DISPLAY 1.021277 (2550 125);
DISPLAY INVISIBLE (2550 125);
FORCEADD VCC_CORE..1
(2500 250);
FORCEPROP 3 LASTPIN (2500 200) SIG_NAME P12V_S3_AUX_CPU1_NVDIMM\g
J 0
(2510 210);
DISPLAY 0.659574 (2510 210);
PAINT MONO (2510 210);
DISPLAY INVISIBLE (2510 210);
FORCEPROP 1 LAST HDL_POWER P12V_S3_AUX_CPU1_NVDIMM
J 1
(2500 300);
DISPLAY 1.148936 (2500 300);
PAINT GREEN (2500 300);
FORCEPROP 2 LAST CDS_LIB logical_power
J 0
(2500 250);
PAINT MONO (2500 250);
DISPLAY INVISIBLE (2500 250);
FORCEPROP 1 LAST PATH I127
J 0
(2550 275);
DISPLAY 0.872340 (2550 275);
PAINT AQUA (2550 275);
DISPLAY INVISIBLE (2550 275);
FORCEADD Q_CAP..1
(3125 -75);
FORCEPROP 1 LAST PART_NUMBER CH6103KEA00
J 0
(3175 -225);
DISPLAY 0.978723 (3175 -225);
DISPLAY INVISIBLE (3175 -225);
FORCEPROP 1 LAST MATERIAL X6S
J 0
(3175 -175);
DISPLAY 0.978723 (3175 -175);
FORCEPROP 1 LAST VALUE 10UF
J 0
(3175 -25);
DISPLAY 0.978723 (3175 -25);
FORCEPROP 1 LAST PACK_TYPE C0805
J 0
(3175 -275);
DISPLAY 0.978723 (3175 -275);
FORCEPROP 1 LAST VOLTAGE 16V
J 0
(3175 -75);
DISPLAY 0.978723 (3175 -75);
FORCEPROP 1 LAST TOLERANCE 10%
J 0
(3175 -125);
DISPLAY 0.978723 (3175 -125);
FORCEPROP 1 LAST $LOCATION C55
J 0
(3175 25);
DISPLAY 0.978723 (3175 25);
FORCEPROP 1 LASTPIN (3125 25) $PN 1
J 0
(3135 5);
DISPLAY 0.787234 (3135 5);
FORCEPROP 1 LASTPIN (3125 -175) $PN 2
J 0
(3135 -195);
DISPLAY 0.787234 (3135 -195);
FORCEPROP 2 LAST CDS_LIB pure_quanta
J 0
(3125 -75);
PAINT MONO (3125 -75);
DISPLAY INVISIBLE (3125 -75);
FORCEPROP 1 LAST PATH I128
J 0
(3175 75);
DISPLAY 0.978723 (3175 75);
PAINT WHITE (3175 75);
DISPLAY INVISIBLE (3175 75);
FORCEPROP 2 LAST CDS_LOCATION C55
J 0
(3175 125);
DISPLAY 1.021277 (3175 125);
DISPLAY INVISIBLE (3175 125);
FORCEPROP 2 LAST $SEC 1
J 0
(3175 125);
DISPLAY 0.680851 (3175 125);
PAINT MONO (3175 125);
DISPLAY INVISIBLE (3175 125);
FORCEPROP 2 LAST CDS_SEC 1
J 0
(3175 125);
DISPLAY 1.021277 (3175 125);
DISPLAY INVISIBLE (3175 125);
FORCEADD TAP..1
(2525 1850);
FORCEPROP 3 LASTPIN (2475 1850) SIG_NAME M_A_CPU1_SB_DQS_DP<0>
J 0
(2485 1860);
DISPLAY 0.659574 (2485 1860);
PAINT MONO (2485 1860);
DISPLAY INVISIBLE (2485 1860);
FORCEPROP 1 LASTPIN (2475 1850) BN 0
J 0
(2463 1858);
DISPLAY 0.680851 (2463 1858);
PAINT GREEN (2463 1858);
FORCEPROP 2 LAST CDS_LIB standard
J 0
(2525 1850);
PAINT MONO (2525 1850);
DISPLAY INVISIBLE (2525 1850);
FORCEPROP 1 LAST BODY_TYPE PLUMBING
J 0
(2525 1900);
DISPLAY 0.872340 (2525 1900);
PAINT GREEN (2525 1900);
DISPLAY INVISIBLE (2525 1900);
FORCEPROP 1 LAST HDL_TAP TRUE
J 0
(2850 1725);
DISPLAY 0.872340 (2850 1725);
DISPLAY INVISIBLE (2850 1725);
FORCEPROP 1 LAST PATH I129
J 0
(2523 1850);
DISPLAY 0.872340 (2523 1850);
PAINT GREEN (2523 1850);
DISPLAY INVISIBLE (2523 1850);
FORCEADD OFFPAGE..3
R 2
(-2800 1975);
FORCEPROP 2 LAST $XR1 98 
J 0
(-3139 1975);
DISPLAY 0.638298 (-3139 1975);
PAINT MONO (-3139 1975);
FORCEPROP 2 LAST $XR0 51 
J 0
(-3049 1975);
DISPLAY 0.638298 (-3049 1975);
PAINT MONO (-3049 1975);
FORCEPROP 2 LAST CDS_LIB standard
J 0
(-2800 1975);
PAINT MONO (-2800 1975);
DISPLAY INVISIBLE (-2800 1975);
FORCEPROP 1 LAST OFFPAGE TRUE
J 2
(-3125 1850);
DISPLAY 0.872340 (-3125 1850);
DISPLAY INVISIBLE (-3125 1850);
FORCEPROP 1 LAST COMMENT_BODY TRUE
J 2
(-2750 1875);
DISPLAY 0.872340 (-2750 1875);
PAINT GREEN (-2750 1875);
DISPLAY INVISIBLE (-2750 1875);
FORCEPROP 2 LAST PATH I13
J 0
(-2750 2050);
DISPLAY 1.021277 (-2750 2050);
DISPLAY INVISIBLE (-2750 2050);
FORCEADD TAP..1
(2700 1900);
FORCEPROP 3 LASTPIN (2650 1900) SIG_NAME M_A_CPU1_SB_DQS_DN<1>
J 0
(2660 1910);
DISPLAY 0.659574 (2660 1910);
PAINT MONO (2660 1910);
DISPLAY INVISIBLE (2660 1910);
FORCEPROP 1 LASTPIN (2650 1900) BN 1
J 0
(2638 1908);
DISPLAY 0.680851 (2638 1908);
PAINT GREEN (2638 1908);
FORCEPROP 2 LAST CDS_LIB standard
J 0
(2700 1900);
DISPLAY INVISIBLE (2700 1900);
FORCEPROP 1 LAST BODY_TYPE PLUMBING
J 0
(2700 1950);
DISPLAY 0.872340 (2700 1950);
PAINT GREEN (2700 1950);
DISPLAY INVISIBLE (2700 1950);
FORCEPROP 1 LAST HDL_TAP TRUE
J 0
(3025 1775);
DISPLAY 0.872340 (3025 1775);
DISPLAY INVISIBLE (3025 1775);
FORCEPROP 1 LAST PATH I130
J 0
(2698 1900);
DISPLAY 0.872340 (2698 1900);
PAINT GREEN (2698 1900);
DISPLAY INVISIBLE (2698 1900);
FORCEADD TAP..1
(2700 1800);
FORCEPROP 3 LASTPIN (2650 1800) SIG_NAME M_A_CPU1_SB_DQS_DN<0>
J 0
(2660 1810);
DISPLAY 0.659574 (2660 1810);
PAINT MONO (2660 1810);
DISPLAY INVISIBLE (2660 1810);
FORCEPROP 1 LASTPIN (2650 1800) BN 0
J 0
(2638 1808);
DISPLAY 0.680851 (2638 1808);
PAINT GREEN (2638 1808);
FORCEPROP 2 LAST CDS_LIB standard
J 0
(2700 1800);
PAINT MONO (2700 1800);
DISPLAY INVISIBLE (2700 1800);
FORCEPROP 1 LAST BODY_TYPE PLUMBING
J 0
(2700 1850);
DISPLAY 0.872340 (2700 1850);
PAINT GREEN (2700 1850);
DISPLAY INVISIBLE (2700 1850);
FORCEPROP 1 LAST HDL_TAP TRUE
J 0
(3025 1675);
DISPLAY 0.872340 (3025 1675);
DISPLAY INVISIBLE (3025 1675);
FORCEPROP 1 LAST PATH I131
J 0
(2698 1800);
DISPLAY 0.872340 (2698 1800);
PAINT GREEN (2698 1800);
DISPLAY INVISIBLE (2698 1800);
FORCEADD TAP..1
(2525 1950);
FORCEPROP 3 LASTPIN (2475 1950) SIG_NAME M_A_CPU1_SB_DQS_DP<1>
J 0
(2485 1960);
DISPLAY 0.659574 (2485 1960);
PAINT MONO (2485 1960);
DISPLAY INVISIBLE (2485 1960);
FORCEPROP 1 LASTPIN (2475 1950) BN 1
J 0
(2463 1958);
DISPLAY 0.680851 (2463 1958);
PAINT GREEN (2463 1958);
FORCEPROP 2 LAST CDS_LIB standard
J 0
(2525 1950);
DISPLAY INVISIBLE (2525 1950);
FORCEPROP 1 LAST BODY_TYPE PLUMBING
J 0
(2525 2000);
DISPLAY 0.872340 (2525 2000);
PAINT GREEN (2525 2000);
DISPLAY INVISIBLE (2525 2000);
FORCEPROP 1 LAST HDL_TAP TRUE
J 0
(2850 1825);
DISPLAY 0.872340 (2850 1825);
DISPLAY INVISIBLE (2850 1825);
FORCEPROP 1 LAST PATH I132
J 0
(2523 1950);
DISPLAY 0.872340 (2523 1950);
PAINT GREEN (2523 1950);
DISPLAY INVISIBLE (2523 1950);
FORCEADD TAP..1
(2525 2150);
FORCEPROP 3 LASTPIN (2475 2150) SIG_NAME M_A_CPU1_SB_DQS_DP<3>
J 0
(2485 2160);
DISPLAY 0.659574 (2485 2160);
PAINT MONO (2485 2160);
DISPLAY INVISIBLE (2485 2160);
FORCEPROP 1 LASTPIN (2475 2150) BN 3
J 0
(2463 2158);
DISPLAY 0.680851 (2463 2158);
PAINT GREEN (2463 2158);
FORCEPROP 2 LAST CDS_LIB standard
J 0
(2525 2150);
PAINT MONO (2525 2150);
DISPLAY INVISIBLE (2525 2150);
FORCEPROP 1 LAST BODY_TYPE PLUMBING
J 0
(2525 2200);
DISPLAY 0.872340 (2525 2200);
PAINT GREEN (2525 2200);
DISPLAY INVISIBLE (2525 2200);
FORCEPROP 1 LAST HDL_TAP TRUE
J 0
(2850 2025);
DISPLAY 0.872340 (2850 2025);
DISPLAY INVISIBLE (2850 2025);
FORCEPROP 1 LAST PATH I133
J 0
(2523 2150);
DISPLAY 0.872340 (2523 2150);
PAINT GREEN (2523 2150);
DISPLAY INVISIBLE (2523 2150);
FORCEADD TAP..1
(2525 2050);
FORCEPROP 3 LASTPIN (2475 2050) SIG_NAME M_A_CPU1_SB_DQS_DP<2>
J 0
(2485 2060);
DISPLAY 0.659574 (2485 2060);
PAINT MONO (2485 2060);
DISPLAY INVISIBLE (2485 2060);
FORCEPROP 1 LASTPIN (2475 2050) BN 2
J 0
(2463 2058);
DISPLAY 0.680851 (2463 2058);
PAINT GREEN (2463 2058);
FORCEPROP 2 LAST CDS_LIB standard
J 0
(2525 2050);
DISPLAY INVISIBLE (2525 2050);
FORCEPROP 1 LAST BODY_TYPE PLUMBING
J 0
(2525 2100);
DISPLAY 0.872340 (2525 2100);
PAINT GREEN (2525 2100);
DISPLAY INVISIBLE (2525 2100);
FORCEPROP 1 LAST HDL_TAP TRUE
J 0
(2850 1925);
DISPLAY 0.872340 (2850 1925);
DISPLAY INVISIBLE (2850 1925);
FORCEPROP 1 LAST PATH I134
J 0
(2523 2050);
DISPLAY 0.872340 (2523 2050);
PAINT GREEN (2523 2050);
DISPLAY INVISIBLE (2523 2050);
FORCEADD TAP..1
(2700 2000);
FORCEPROP 3 LASTPIN (2650 2000) SIG_NAME M_A_CPU1_SB_DQS_DN<2>
J 0
(2660 2010);
DISPLAY 0.659574 (2660 2010);
PAINT MONO (2660 2010);
DISPLAY INVISIBLE (2660 2010);
FORCEPROP 1 LASTPIN (2650 2000) BN 2
J 0
(2638 2008);
DISPLAY 0.680851 (2638 2008);
PAINT GREEN (2638 2008);
FORCEPROP 2 LAST CDS_LIB standard
J 0
(2700 2000);
DISPLAY INVISIBLE (2700 2000);
FORCEPROP 1 LAST BODY_TYPE PLUMBING
J 0
(2700 2050);
DISPLAY 0.872340 (2700 2050);
PAINT GREEN (2700 2050);
DISPLAY INVISIBLE (2700 2050);
FORCEPROP 1 LAST HDL_TAP TRUE
J 0
(3025 1875);
DISPLAY 0.872340 (3025 1875);
DISPLAY INVISIBLE (3025 1875);
FORCEPROP 1 LAST PATH I135
J 0
(2698 2000);
DISPLAY 0.872340 (2698 2000);
PAINT GREEN (2698 2000);
DISPLAY INVISIBLE (2698 2000);
FORCEADD TAP..1
(2700 2100);
FORCEPROP 3 LASTPIN (2650 2100) SIG_NAME M_A_CPU1_SB_DQS_DN<3>
J 0
(2660 2110);
DISPLAY 0.659574 (2660 2110);
PAINT MONO (2660 2110);
DISPLAY INVISIBLE (2660 2110);
FORCEPROP 1 LASTPIN (2650 2100) BN 3
J 0
(2638 2108);
DISPLAY 0.680851 (2638 2108);
PAINT GREEN (2638 2108);
FORCEPROP 2 LAST CDS_LIB standard
J 0
(2700 2100);
PAINT MONO (2700 2100);
DISPLAY INVISIBLE (2700 2100);
FORCEPROP 1 LAST BODY_TYPE PLUMBING
J 0
(2700 2150);
DISPLAY 0.872340 (2700 2150);
PAINT GREEN (2700 2150);
DISPLAY INVISIBLE (2700 2150);
FORCEPROP 1 LAST HDL_TAP TRUE
J 0
(3025 1975);
DISPLAY 0.872340 (3025 1975);
DISPLAY INVISIBLE (3025 1975);
FORCEPROP 1 LAST PATH I136
J 0
(2698 2100);
DISPLAY 0.872340 (2698 2100);
PAINT GREEN (2698 2100);
DISPLAY INVISIBLE (2698 2100);
FORCEADD TAP..1
(2525 2250);
FORCEPROP 3 LASTPIN (2475 2250) SIG_NAME M_A_CPU1_SB_DQS_DP<4>
J 0
(2485 2260);
DISPLAY 0.659574 (2485 2260);
PAINT MONO (2485 2260);
DISPLAY INVISIBLE (2485 2260);
FORCEPROP 1 LASTPIN (2475 2250) BN 4
J 0
(2463 2258);
DISPLAY 0.680851 (2463 2258);
PAINT GREEN (2463 2258);
FORCEPROP 2 LAST CDS_LIB standard
J 0
(2525 2250);
PAINT MONO (2525 2250);
DISPLAY INVISIBLE (2525 2250);
FORCEPROP 1 LAST BODY_TYPE PLUMBING
J 0
(2525 2300);
DISPLAY 0.872340 (2525 2300);
PAINT GREEN (2525 2300);
DISPLAY INVISIBLE (2525 2300);
FORCEPROP 1 LAST HDL_TAP TRUE
J 0
(2850 2125);
DISPLAY 0.872340 (2850 2125);
DISPLAY INVISIBLE (2850 2125);
FORCEPROP 1 LAST PATH I137
J 0
(2523 2250);
DISPLAY 0.872340 (2523 2250);
PAINT GREEN (2523 2250);
DISPLAY INVISIBLE (2523 2250);
FORCEADD TAP..1
(2525 2350);
FORCEPROP 3 LASTPIN (2475 2350) SIG_NAME M_A_CPU1_SB_DQS_DP<5>
J 0
(2485 2360);
DISPLAY 0.659574 (2485 2360);
PAINT MONO (2485 2360);
DISPLAY INVISIBLE (2485 2360);
FORCEPROP 1 LASTPIN (2475 2350) BN 5
J 0
(2463 2358);
DISPLAY 0.680851 (2463 2358);
PAINT GREEN (2463 2358);
FORCEPROP 2 LAST CDS_LIB standard
J 0
(2525 2350);
DISPLAY INVISIBLE (2525 2350);
FORCEPROP 1 LAST BODY_TYPE PLUMBING
J 0
(2525 2400);
DISPLAY 0.872340 (2525 2400);
PAINT GREEN (2525 2400);
DISPLAY INVISIBLE (2525 2400);
FORCEPROP 1 LAST HDL_TAP TRUE
J 0
(2850 2225);
DISPLAY 0.872340 (2850 2225);
DISPLAY INVISIBLE (2850 2225);
FORCEPROP 1 LAST PATH I138
J 0
(2523 2350);
DISPLAY 0.872340 (2523 2350);
PAINT GREEN (2523 2350);
DISPLAY INVISIBLE (2523 2350);
FORCEADD TAP..1
(2700 2200);
FORCEPROP 3 LASTPIN (2650 2200) SIG_NAME M_A_CPU1_SB_DQS_DN<4>
J 0
(2660 2210);
DISPLAY 0.659574 (2660 2210);
PAINT MONO (2660 2210);
DISPLAY INVISIBLE (2660 2210);
FORCEPROP 1 LASTPIN (2650 2200) BN 4
J 0
(2638 2208);
DISPLAY 0.680851 (2638 2208);
PAINT GREEN (2638 2208);
FORCEPROP 2 LAST CDS_LIB standard
J 0
(2700 2200);
PAINT MONO (2700 2200);
DISPLAY INVISIBLE (2700 2200);
FORCEPROP 1 LAST BODY_TYPE PLUMBING
J 0
(2700 2250);
DISPLAY 0.872340 (2700 2250);
PAINT GREEN (2700 2250);
DISPLAY INVISIBLE (2700 2250);
FORCEPROP 1 LAST HDL_TAP TRUE
J 0
(3025 2075);
DISPLAY 0.872340 (3025 2075);
DISPLAY INVISIBLE (3025 2075);
FORCEPROP 1 LAST PATH I139
J 0
(2698 2200);
DISPLAY 0.872340 (2698 2200);
PAINT GREEN (2698 2200);
DISPLAY INVISIBLE (2698 2200);
FORCEADD OFFPAGE..3
R 2
(-2800 2425);
FORCEPROP 2 LAST $XR1 98 
J 0
(-3139 2425);
DISPLAY 0.638298 (-3139 2425);
PAINT MONO (-3139 2425);
FORCEPROP 2 LAST $XR0 51 
J 0
(-3049 2425);
DISPLAY 0.638298 (-3049 2425);
PAINT MONO (-3049 2425);
FORCEPROP 2 LAST CDS_LIB standard
J 0
(-2800 2425);
PAINT MONO (-2800 2425);
DISPLAY INVISIBLE (-2800 2425);
FORCEPROP 1 LAST OFFPAGE TRUE
J 2
(-3125 2300);
DISPLAY 0.872340 (-3125 2300);
DISPLAY INVISIBLE (-3125 2300);
FORCEPROP 1 LAST COMMENT_BODY TRUE
J 2
(-2750 2325);
DISPLAY 0.872340 (-2750 2325);
PAINT GREEN (-2750 2325);
DISPLAY INVISIBLE (-2750 2325);
FORCEPROP 2 LAST PATH I14
J 0
(-2750 2500);
DISPLAY 1.021277 (-2750 2500);
DISPLAY INVISIBLE (-2750 2500);
FORCEADD TAP..1
(2700 2300);
FORCEPROP 3 LASTPIN (2650 2300) SIG_NAME M_A_CPU1_SB_DQS_DN<5>
J 0
(2660 2310);
DISPLAY 0.659574 (2660 2310);
PAINT MONO (2660 2310);
DISPLAY INVISIBLE (2660 2310);
FORCEPROP 1 LASTPIN (2650 2300) BN 5
J 0
(2638 2308);
DISPLAY 0.680851 (2638 2308);
PAINT GREEN (2638 2308);
FORCEPROP 2 LAST CDS_LIB standard
J 0
(2700 2300);
DISPLAY INVISIBLE (2700 2300);
FORCEPROP 1 LAST BODY_TYPE PLUMBING
J 0
(2700 2350);
DISPLAY 0.872340 (2700 2350);
PAINT GREEN (2700 2350);
DISPLAY INVISIBLE (2700 2350);
FORCEPROP 1 LAST HDL_TAP TRUE
J 0
(3025 2175);
DISPLAY 0.872340 (3025 2175);
DISPLAY INVISIBLE (3025 2175);
FORCEPROP 1 LAST PATH I140
J 0
(2698 2300);
DISPLAY 0.872340 (2698 2300);
PAINT GREEN (2698 2300);
DISPLAY INVISIBLE (2698 2300);
FORCEADD TAP..1
(2700 2400);
FORCEPROP 3 LASTPIN (2650 2400) SIG_NAME M_A_CPU1_SB_DQS_DN<6>
J 0
(2660 2410);
DISPLAY 0.659574 (2660 2410);
PAINT MONO (2660 2410);
DISPLAY INVISIBLE (2660 2410);
FORCEPROP 1 LASTPIN (2650 2400) BN 6
J 0
(2638 2408);
DISPLAY 0.680851 (2638 2408);
PAINT GREEN (2638 2408);
FORCEPROP 2 LAST CDS_LIB standard
J 0
(2700 2400);
DISPLAY INVISIBLE (2700 2400);
FORCEPROP 1 LAST BODY_TYPE PLUMBING
J 0
(2700 2450);
DISPLAY 0.872340 (2700 2450);
PAINT GREEN (2700 2450);
DISPLAY INVISIBLE (2700 2450);
FORCEPROP 1 LAST HDL_TAP TRUE
J 0
(3025 2275);
DISPLAY 0.872340 (3025 2275);
DISPLAY INVISIBLE (3025 2275);
FORCEPROP 1 LAST PATH I141
J 0
(2698 2400);
DISPLAY 0.872340 (2698 2400);
PAINT GREEN (2698 2400);
DISPLAY INVISIBLE (2698 2400);
FORCEADD TAP..1
(2525 2450);
FORCEPROP 3 LASTPIN (2475 2450) SIG_NAME M_A_CPU1_SB_DQS_DP<6>
J 0
(2485 2460);
DISPLAY 0.659574 (2485 2460);
PAINT MONO (2485 2460);
DISPLAY INVISIBLE (2485 2460);
FORCEPROP 1 LASTPIN (2475 2450) BN 6
J 0
(2463 2458);
DISPLAY 0.680851 (2463 2458);
PAINT GREEN (2463 2458);
FORCEPROP 2 LAST CDS_LIB standard
J 0
(2525 2450);
DISPLAY INVISIBLE (2525 2450);
FORCEPROP 1 LAST BODY_TYPE PLUMBING
J 0
(2525 2500);
DISPLAY 0.872340 (2525 2500);
PAINT GREEN (2525 2500);
DISPLAY INVISIBLE (2525 2500);
FORCEPROP 1 LAST HDL_TAP TRUE
J 0
(2850 2325);
DISPLAY 0.872340 (2850 2325);
DISPLAY INVISIBLE (2850 2325);
FORCEPROP 1 LAST PATH I142
J 0
(2523 2450);
DISPLAY 0.872340 (2523 2450);
PAINT GREEN (2523 2450);
DISPLAY INVISIBLE (2523 2450);
FORCEADD TAP..1
(2525 2650);
FORCEPROP 3 LASTPIN (2475 2650) SIG_NAME M_A_CPU1_SB_DQS_DP<8>
J 0
(2485 2660);
DISPLAY 0.659574 (2485 2660);
PAINT MONO (2485 2660);
DISPLAY INVISIBLE (2485 2660);
FORCEPROP 1 LASTPIN (2475 2650) BN 8
J 0
(2463 2658);
DISPLAY 0.680851 (2463 2658);
PAINT GREEN (2463 2658);
FORCEPROP 2 LAST CDS_LIB standard
J 0
(2525 2650);
DISPLAY INVISIBLE (2525 2650);
FORCEPROP 1 LAST BODY_TYPE PLUMBING
J 0
(2525 2700);
DISPLAY 0.872340 (2525 2700);
PAINT GREEN (2525 2700);
DISPLAY INVISIBLE (2525 2700);
FORCEPROP 1 LAST HDL_TAP TRUE
J 0
(2850 2525);
DISPLAY 0.872340 (2850 2525);
DISPLAY INVISIBLE (2850 2525);
FORCEPROP 1 LAST PATH I143
J 0
(2523 2650);
DISPLAY 0.872340 (2523 2650);
PAINT GREEN (2523 2650);
DISPLAY INVISIBLE (2523 2650);
FORCEADD TAP..1
(2525 2550);
FORCEPROP 3 LASTPIN (2475 2550) SIG_NAME M_A_CPU1_SB_DQS_DP<7>
J 0
(2485 2560);
DISPLAY 0.659574 (2485 2560);
PAINT MONO (2485 2560);
DISPLAY INVISIBLE (2485 2560);
FORCEPROP 1 LASTPIN (2475 2550) BN 7
J 0
(2463 2558);
DISPLAY 0.680851 (2463 2558);
PAINT GREEN (2463 2558);
FORCEPROP 2 LAST CDS_LIB standard
J 0
(2525 2550);
DISPLAY INVISIBLE (2525 2550);
FORCEPROP 1 LAST BODY_TYPE PLUMBING
J 0
(2525 2600);
DISPLAY 0.872340 (2525 2600);
PAINT GREEN (2525 2600);
DISPLAY INVISIBLE (2525 2600);
FORCEPROP 1 LAST HDL_TAP TRUE
J 0
(2850 2425);
DISPLAY 0.872340 (2850 2425);
DISPLAY INVISIBLE (2850 2425);
FORCEPROP 1 LAST PATH I144
J 0
(2523 2550);
DISPLAY 0.872340 (2523 2550);
PAINT GREEN (2523 2550);
DISPLAY INVISIBLE (2523 2550);
FORCEADD TAP..1
(2700 2500);
FORCEPROP 3 LASTPIN (2650 2500) SIG_NAME M_A_CPU1_SB_DQS_DN<7>
J 0
(2660 2510);
DISPLAY 0.659574 (2660 2510);
PAINT MONO (2660 2510);
DISPLAY INVISIBLE (2660 2510);
FORCEPROP 1 LASTPIN (2650 2500) BN 7
J 0
(2638 2508);
DISPLAY 0.680851 (2638 2508);
PAINT GREEN (2638 2508);
FORCEPROP 2 LAST CDS_LIB standard
J 0
(2700 2500);
DISPLAY INVISIBLE (2700 2500);
FORCEPROP 1 LAST BODY_TYPE PLUMBING
J 0
(2700 2550);
DISPLAY 0.872340 (2700 2550);
PAINT GREEN (2700 2550);
DISPLAY INVISIBLE (2700 2550);
FORCEPROP 1 LAST HDL_TAP TRUE
J 0
(3025 2375);
DISPLAY 0.872340 (3025 2375);
DISPLAY INVISIBLE (3025 2375);
FORCEPROP 1 LAST PATH I145
J 0
(2698 2500);
DISPLAY 0.872340 (2698 2500);
PAINT GREEN (2698 2500);
DISPLAY INVISIBLE (2698 2500);
FORCEADD TAP..1
(2700 2600);
FORCEPROP 3 LASTPIN (2650 2600) SIG_NAME M_A_CPU1_SB_DQS_DN<8>
J 0
(2660 2610);
DISPLAY 0.659574 (2660 2610);
PAINT MONO (2660 2610);
DISPLAY INVISIBLE (2660 2610);
FORCEPROP 1 LASTPIN (2650 2600) BN 8
J 0
(2638 2608);
DISPLAY 0.680851 (2638 2608);
PAINT GREEN (2638 2608);
FORCEPROP 2 LAST CDS_LIB standard
J 0
(2700 2600);
DISPLAY INVISIBLE (2700 2600);
FORCEPROP 1 LAST BODY_TYPE PLUMBING
J 0
(2700 2650);
DISPLAY 0.872340 (2700 2650);
PAINT GREEN (2700 2650);
DISPLAY INVISIBLE (2700 2650);
FORCEPROP 1 LAST HDL_TAP TRUE
J 0
(3025 2475);
DISPLAY 0.872340 (3025 2475);
DISPLAY INVISIBLE (3025 2475);
FORCEPROP 1 LAST PATH I146
J 0
(2698 2600);
DISPLAY 0.872340 (2698 2600);
PAINT GREEN (2698 2600);
DISPLAY INVISIBLE (2698 2600);
FORCEADD TAP..1
(2525 2750);
FORCEPROP 3 LASTPIN (2475 2750) SIG_NAME M_A_CPU1_SB_DQS_DP<9>
J 0
(2485 2760);
DISPLAY 0.659574 (2485 2760);
PAINT MONO (2485 2760);
DISPLAY INVISIBLE (2485 2760);
FORCEPROP 1 LASTPIN (2475 2750) BN 9
J 0
(2463 2758);
DISPLAY 0.680851 (2463 2758);
PAINT GREEN (2463 2758);
FORCEPROP 2 LAST CDS_LIB standard
J 0
(2525 2750);
DISPLAY INVISIBLE (2525 2750);
FORCEPROP 1 LAST BODY_TYPE PLUMBING
J 0
(2525 2800);
DISPLAY 0.872340 (2525 2800);
PAINT GREEN (2525 2800);
DISPLAY INVISIBLE (2525 2800);
FORCEPROP 1 LAST HDL_TAP TRUE
J 0
(2850 2625);
DISPLAY 0.872340 (2850 2625);
DISPLAY INVISIBLE (2850 2625);
FORCEPROP 1 LAST PATH I147
J 0
(2523 2750);
DISPLAY 0.872340 (2523 2750);
PAINT GREEN (2523 2750);
DISPLAY INVISIBLE (2523 2750);
FORCEADD TAP..1
(2525 2900);
FORCEPROP 3 LASTPIN (2475 2900) SIG_NAME M_A_CPU1_SA_DQS_DP<0>
J 0
(2485 2910);
DISPLAY 0.659574 (2485 2910);
PAINT MONO (2485 2910);
DISPLAY INVISIBLE (2485 2910);
FORCEPROP 1 LASTPIN (2475 2900) BN 0
J 0
(2463 2908);
DISPLAY 0.680851 (2463 2908);
PAINT GREEN (2463 2908);
FORCEPROP 2 LAST CDS_LIB standard
J 0
(2525 2900);
PAINT MONO (2525 2900);
DISPLAY INVISIBLE (2525 2900);
FORCEPROP 1 LAST BODY_TYPE PLUMBING
J 0
(2525 2950);
DISPLAY 0.872340 (2525 2950);
PAINT GREEN (2525 2950);
DISPLAY INVISIBLE (2525 2950);
FORCEPROP 1 LAST HDL_TAP TRUE
J 0
(2850 2775);
DISPLAY 0.872340 (2850 2775);
DISPLAY INVISIBLE (2850 2775);
FORCEPROP 1 LAST PATH I148
J 0
(2523 2900);
DISPLAY 0.872340 (2523 2900);
PAINT GREEN (2523 2900);
DISPLAY INVISIBLE (2523 2900);
FORCEADD TAP..1
(2700 2700);
FORCEPROP 3 LASTPIN (2650 2700) SIG_NAME M_A_CPU1_SB_DQS_DN<9>
J 0
(2660 2710);
DISPLAY 0.659574 (2660 2710);
PAINT MONO (2660 2710);
DISPLAY INVISIBLE (2660 2710);
FORCEPROP 1 LASTPIN (2650 2700) BN 9
J 0
(2638 2708);
DISPLAY 0.680851 (2638 2708);
PAINT GREEN (2638 2708);
FORCEPROP 2 LAST CDS_LIB standard
J 0
(2700 2700);
DISPLAY INVISIBLE (2700 2700);
FORCEPROP 1 LAST BODY_TYPE PLUMBING
J 0
(2700 2750);
DISPLAY 0.872340 (2700 2750);
PAINT GREEN (2700 2750);
DISPLAY INVISIBLE (2700 2750);
FORCEPROP 1 LAST HDL_TAP TRUE
J 0
(3025 2575);
DISPLAY 0.872340 (3025 2575);
DISPLAY INVISIBLE (3025 2575);
FORCEPROP 1 LAST PATH I149
J 0
(2698 2700);
DISPLAY 0.872340 (2698 2700);
PAINT GREEN (2698 2700);
DISPLAY INVISIBLE (2698 2700);
FORCEADD OFFPAGE..1
(-2800 2550);
FORCEPROP 2 LAST $XR0 51 
J 0
(-3021 2550);
DISPLAY 0.638298 (-3021 2550);
PAINT MONO (-3021 2550);
FORCEPROP 2 LAST CDS_LIB standard
J 0
(-2800 2550);
PAINT MONO (-2800 2550);
DISPLAY INVISIBLE (-2800 2550);
FORCEPROP 1 LAST OFFPAGE TRUE
J 0
(-2475 2425);
DISPLAY 0.872340 (-2475 2425);
DISPLAY INVISIBLE (-2475 2425);
FORCEPROP 1 LAST COMMENT_BODY TRUE
J 0
(-2675 2450);
DISPLAY 0.872340 (-2675 2450);
PAINT GREEN (-2675 2450);
DISPLAY INVISIBLE (-2675 2450);
FORCEPROP 2 LAST PATH I15
J 0
(-2750 2625);
DISPLAY 1.021277 (-2750 2625);
DISPLAY INVISIBLE (-2750 2625);
FORCEADD TAP..1
(2700 2850);
FORCEPROP 3 LASTPIN (2650 2850) SIG_NAME M_A_CPU1_SA_DQS_DN<0>
J 0
(2660 2860);
DISPLAY 0.659574 (2660 2860);
PAINT MONO (2660 2860);
DISPLAY INVISIBLE (2660 2860);
FORCEPROP 1 LASTPIN (2650 2850) BN 0
J 0
(2638 2858);
DISPLAY 0.680851 (2638 2858);
PAINT GREEN (2638 2858);
FORCEPROP 2 LAST CDS_LIB standard
J 0
(2700 2850);
PAINT MONO (2700 2850);
DISPLAY INVISIBLE (2700 2850);
FORCEPROP 1 LAST BODY_TYPE PLUMBING
J 0
(2700 2900);
DISPLAY 0.872340 (2700 2900);
PAINT GREEN (2700 2900);
DISPLAY INVISIBLE (2700 2900);
FORCEPROP 1 LAST HDL_TAP TRUE
J 0
(3025 2725);
DISPLAY 0.872340 (3025 2725);
DISPLAY INVISIBLE (3025 2725);
FORCEPROP 1 LAST PATH I150
J 0
(2698 2850);
DISPLAY 0.872340 (2698 2850);
PAINT GREEN (2698 2850);
DISPLAY INVISIBLE (2698 2850);
FORCEADD TAP..1
(2525 3000);
FORCEPROP 3 LASTPIN (2475 3000) SIG_NAME M_A_CPU1_SA_DQS_DP<1>
J 0
(2485 3010);
DISPLAY 0.659574 (2485 3010);
PAINT MONO (2485 3010);
DISPLAY INVISIBLE (2485 3010);
FORCEPROP 1 LASTPIN (2475 3000) BN 1
J 0
(2463 3008);
DISPLAY 0.680851 (2463 3008);
PAINT GREEN (2463 3008);
FORCEPROP 2 LAST CDS_LIB standard
J 0
(2525 3000);
DISPLAY INVISIBLE (2525 3000);
FORCEPROP 1 LAST BODY_TYPE PLUMBING
J 0
(2525 3050);
DISPLAY 0.872340 (2525 3050);
PAINT GREEN (2525 3050);
DISPLAY INVISIBLE (2525 3050);
FORCEPROP 1 LAST HDL_TAP TRUE
J 0
(2850 2875);
DISPLAY 0.872340 (2850 2875);
DISPLAY INVISIBLE (2850 2875);
FORCEPROP 1 LAST PATH I151
J 0
(2523 3000);
DISPLAY 0.872340 (2523 3000);
PAINT GREEN (2523 3000);
DISPLAY INVISIBLE (2523 3000);
FORCEADD TAP..1
(2525 3100);
FORCEPROP 3 LASTPIN (2475 3100) SIG_NAME M_A_CPU1_SA_DQS_DP<2>
J 0
(2485 3110);
DISPLAY 0.659574 (2485 3110);
PAINT MONO (2485 3110);
DISPLAY INVISIBLE (2485 3110);
FORCEPROP 1 LASTPIN (2475 3100) BN 2
J 0
(2463 3108);
DISPLAY 0.680851 (2463 3108);
PAINT GREEN (2463 3108);
FORCEPROP 2 LAST CDS_LIB standard
J 0
(2525 3100);
DISPLAY INVISIBLE (2525 3100);
FORCEPROP 1 LAST BODY_TYPE PLUMBING
J 0
(2525 3150);
DISPLAY 0.872340 (2525 3150);
PAINT GREEN (2525 3150);
DISPLAY INVISIBLE (2525 3150);
FORCEPROP 1 LAST HDL_TAP TRUE
J 0
(2850 2975);
DISPLAY 0.872340 (2850 2975);
DISPLAY INVISIBLE (2850 2975);
FORCEPROP 1 LAST PATH I152
J 0
(2523 3100);
DISPLAY 0.872340 (2523 3100);
PAINT GREEN (2523 3100);
DISPLAY INVISIBLE (2523 3100);
FORCEADD TAP..1
(2700 2950);
FORCEPROP 3 LASTPIN (2650 2950) SIG_NAME M_A_CPU1_SA_DQS_DN<1>
J 0
(2660 2960);
DISPLAY 0.659574 (2660 2960);
PAINT MONO (2660 2960);
DISPLAY INVISIBLE (2660 2960);
FORCEPROP 1 LASTPIN (2650 2950) BN 1
J 0
(2638 2958);
DISPLAY 0.680851 (2638 2958);
PAINT GREEN (2638 2958);
FORCEPROP 2 LAST CDS_LIB standard
J 0
(2700 2950);
DISPLAY INVISIBLE (2700 2950);
FORCEPROP 1 LAST BODY_TYPE PLUMBING
J 0
(2700 3000);
DISPLAY 0.872340 (2700 3000);
PAINT GREEN (2700 3000);
DISPLAY INVISIBLE (2700 3000);
FORCEPROP 1 LAST HDL_TAP TRUE
J 0
(3025 2825);
DISPLAY 0.872340 (3025 2825);
DISPLAY INVISIBLE (3025 2825);
FORCEPROP 1 LAST PATH I153
J 0
(2698 2950);
DISPLAY 0.872340 (2698 2950);
PAINT GREEN (2698 2950);
DISPLAY INVISIBLE (2698 2950);
FORCEADD TAP..1
(2700 3050);
FORCEPROP 3 LASTPIN (2650 3050) SIG_NAME M_A_CPU1_SA_DQS_DN<2>
J 0
(2660 3060);
DISPLAY 0.659574 (2660 3060);
PAINT MONO (2660 3060);
DISPLAY INVISIBLE (2660 3060);
FORCEPROP 1 LASTPIN (2650 3050) BN 2
J 0
(2638 3058);
DISPLAY 0.680851 (2638 3058);
PAINT GREEN (2638 3058);
FORCEPROP 2 LAST CDS_LIB standard
J 0
(2700 3050);
DISPLAY INVISIBLE (2700 3050);
FORCEPROP 1 LAST BODY_TYPE PLUMBING
J 0
(2700 3100);
DISPLAY 0.872340 (2700 3100);
PAINT GREEN (2700 3100);
DISPLAY INVISIBLE (2700 3100);
FORCEPROP 1 LAST HDL_TAP TRUE
J 0
(3025 2925);
DISPLAY 0.872340 (3025 2925);
DISPLAY INVISIBLE (3025 2925);
FORCEPROP 1 LAST PATH I154
J 0
(2698 3050);
DISPLAY 0.872340 (2698 3050);
PAINT GREEN (2698 3050);
DISPLAY INVISIBLE (2698 3050);
FORCEADD TAP..1
(2700 3150);
FORCEPROP 3 LASTPIN (2650 3150) SIG_NAME M_A_CPU1_SA_DQS_DN<3>
J 0
(2660 3160);
DISPLAY 0.659574 (2660 3160);
PAINT MONO (2660 3160);
DISPLAY INVISIBLE (2660 3160);
FORCEPROP 1 LASTPIN (2650 3150) BN 3
J 0
(2638 3158);
DISPLAY 0.680851 (2638 3158);
PAINT GREEN (2638 3158);
FORCEPROP 2 LAST CDS_LIB standard
J 0
(2700 3150);
PAINT MONO (2700 3150);
DISPLAY INVISIBLE (2700 3150);
FORCEPROP 1 LAST BODY_TYPE PLUMBING
J 0
(2700 3200);
DISPLAY 0.872340 (2700 3200);
PAINT GREEN (2700 3200);
DISPLAY INVISIBLE (2700 3200);
FORCEPROP 1 LAST HDL_TAP TRUE
J 0
(3025 3025);
DISPLAY 0.872340 (3025 3025);
DISPLAY INVISIBLE (3025 3025);
FORCEPROP 1 LAST PATH I155
J 0
(2698 3150);
DISPLAY 0.872340 (2698 3150);
PAINT GREEN (2698 3150);
DISPLAY INVISIBLE (2698 3150);
FORCEADD TAP..1
(2525 3300);
FORCEPROP 3 LASTPIN (2475 3300) SIG_NAME M_A_CPU1_SA_DQS_DP<4>
J 0
(2485 3310);
DISPLAY 0.659574 (2485 3310);
PAINT MONO (2485 3310);
DISPLAY INVISIBLE (2485 3310);
FORCEPROP 1 LASTPIN (2475 3300) BN 4
J 0
(2463 3308);
DISPLAY 0.680851 (2463 3308);
PAINT GREEN (2463 3308);
FORCEPROP 2 LAST CDS_LIB standard
J 0
(2525 3300);
PAINT MONO (2525 3300);
DISPLAY INVISIBLE (2525 3300);
FORCEPROP 1 LAST BODY_TYPE PLUMBING
J 0
(2525 3350);
DISPLAY 0.872340 (2525 3350);
PAINT GREEN (2525 3350);
DISPLAY INVISIBLE (2525 3350);
FORCEPROP 1 LAST HDL_TAP TRUE
J 0
(2850 3175);
DISPLAY 0.872340 (2850 3175);
DISPLAY INVISIBLE (2850 3175);
FORCEPROP 1 LAST PATH I156
J 0
(2523 3300);
DISPLAY 0.872340 (2523 3300);
PAINT GREEN (2523 3300);
DISPLAY INVISIBLE (2523 3300);
FORCEADD TAP..1
(2525 3200);
FORCEPROP 3 LASTPIN (2475 3200) SIG_NAME M_A_CPU1_SA_DQS_DP<3>
J 0
(2485 3210);
DISPLAY 0.659574 (2485 3210);
PAINT MONO (2485 3210);
DISPLAY INVISIBLE (2485 3210);
FORCEPROP 1 LASTPIN (2475 3200) BN 3
J 0
(2463 3208);
DISPLAY 0.680851 (2463 3208);
PAINT GREEN (2463 3208);
FORCEPROP 2 LAST CDS_LIB standard
J 0
(2525 3200);
PAINT MONO (2525 3200);
DISPLAY INVISIBLE (2525 3200);
FORCEPROP 1 LAST BODY_TYPE PLUMBING
J 0
(2525 3250);
DISPLAY 0.872340 (2525 3250);
PAINT GREEN (2525 3250);
DISPLAY INVISIBLE (2525 3250);
FORCEPROP 1 LAST HDL_TAP TRUE
J 0
(2850 3075);
DISPLAY 0.872340 (2850 3075);
DISPLAY INVISIBLE (2850 3075);
FORCEPROP 1 LAST PATH I157
J 0
(2523 3200);
DISPLAY 0.872340 (2523 3200);
PAINT GREEN (2523 3200);
DISPLAY INVISIBLE (2523 3200);
FORCEADD TAP..1
(2525 3400);
FORCEPROP 3 LASTPIN (2475 3400) SIG_NAME M_A_CPU1_SA_DQS_DP<5>
J 0
(2485 3410);
DISPLAY 0.659574 (2485 3410);
PAINT MONO (2485 3410);
DISPLAY INVISIBLE (2485 3410);
FORCEPROP 1 LASTPIN (2475 3400) BN 5
J 0
(2463 3408);
DISPLAY 0.680851 (2463 3408);
PAINT GREEN (2463 3408);
FORCEPROP 2 LAST CDS_LIB standard
J 0
(2525 3400);
DISPLAY INVISIBLE (2525 3400);
FORCEPROP 1 LAST BODY_TYPE PLUMBING
J 0
(2525 3450);
DISPLAY 0.872340 (2525 3450);
PAINT GREEN (2525 3450);
DISPLAY INVISIBLE (2525 3450);
FORCEPROP 1 LAST HDL_TAP TRUE
J 0
(2850 3275);
DISPLAY 0.872340 (2850 3275);
DISPLAY INVISIBLE (2850 3275);
FORCEPROP 1 LAST PATH I158
J 0
(2523 3400);
DISPLAY 0.872340 (2523 3400);
PAINT GREEN (2523 3400);
DISPLAY INVISIBLE (2523 3400);
FORCEADD TAP..1
(2700 3250);
FORCEPROP 3 LASTPIN (2650 3250) SIG_NAME M_A_CPU1_SA_DQS_DN<4>
J 0
(2660 3260);
DISPLAY 0.659574 (2660 3260);
PAINT MONO (2660 3260);
DISPLAY INVISIBLE (2660 3260);
FORCEPROP 1 LASTPIN (2650 3250) BN 4
J 0
(2638 3258);
DISPLAY 0.680851 (2638 3258);
PAINT GREEN (2638 3258);
FORCEPROP 2 LAST CDS_LIB standard
J 0
(2700 3250);
PAINT MONO (2700 3250);
DISPLAY INVISIBLE (2700 3250);
FORCEPROP 1 LAST BODY_TYPE PLUMBING
J 0
(2700 3300);
DISPLAY 0.872340 (2700 3300);
PAINT GREEN (2700 3300);
DISPLAY INVISIBLE (2700 3300);
FORCEPROP 1 LAST HDL_TAP TRUE
J 0
(3025 3125);
DISPLAY 0.872340 (3025 3125);
DISPLAY INVISIBLE (3025 3125);
FORCEPROP 1 LAST PATH I159
J 0
(2698 3250);
DISPLAY 0.872340 (2698 3250);
PAINT GREEN (2698 3250);
DISPLAY INVISIBLE (2698 3250);
FORCEADD OFFPAGE..1
(-2800 2500);
FORCEPROP 2 LAST $XR0 51 
J 0
(-3021 2500);
DISPLAY 0.638298 (-3021 2500);
PAINT MONO (-3021 2500);
FORCEPROP 2 LAST CDS_LIB standard
J 0
(-2800 2500);
PAINT MONO (-2800 2500);
DISPLAY INVISIBLE (-2800 2500);
FORCEPROP 1 LAST OFFPAGE TRUE
J 0
(-2475 2375);
DISPLAY 0.872340 (-2475 2375);
DISPLAY INVISIBLE (-2475 2375);
FORCEPROP 1 LAST COMMENT_BODY TRUE
J 0
(-2675 2400);
DISPLAY 0.872340 (-2675 2400);
PAINT GREEN (-2675 2400);
DISPLAY INVISIBLE (-2675 2400);
FORCEPROP 2 LAST PATH I16
J 0
(-2750 2575);
DISPLAY 1.021277 (-2750 2575);
DISPLAY INVISIBLE (-2750 2575);
FORCEADD TAP..1
(2700 3350);
FORCEPROP 3 LASTPIN (2650 3350) SIG_NAME M_A_CPU1_SA_DQS_DN<5>
J 0
(2660 3360);
DISPLAY 0.659574 (2660 3360);
PAINT MONO (2660 3360);
DISPLAY INVISIBLE (2660 3360);
FORCEPROP 1 LASTPIN (2650 3350) BN 5
J 0
(2638 3358);
DISPLAY 0.680851 (2638 3358);
PAINT GREEN (2638 3358);
FORCEPROP 2 LAST CDS_LIB standard
J 0
(2700 3350);
DISPLAY INVISIBLE (2700 3350);
FORCEPROP 1 LAST BODY_TYPE PLUMBING
J 0
(2700 3400);
DISPLAY 0.872340 (2700 3400);
PAINT GREEN (2700 3400);
DISPLAY INVISIBLE (2700 3400);
FORCEPROP 1 LAST HDL_TAP TRUE
J 0
(3025 3225);
DISPLAY 0.872340 (3025 3225);
DISPLAY INVISIBLE (3025 3225);
FORCEPROP 1 LAST PATH I160
J 0
(2698 3350);
DISPLAY 0.872340 (2698 3350);
PAINT GREEN (2698 3350);
DISPLAY INVISIBLE (2698 3350);
FORCEADD TAP..1
(2525 3500);
FORCEPROP 3 LASTPIN (2475 3500) SIG_NAME M_A_CPU1_SA_DQS_DP<6>
J 0
(2485 3510);
DISPLAY 0.659574 (2485 3510);
PAINT MONO (2485 3510);
DISPLAY INVISIBLE (2485 3510);
FORCEPROP 1 LASTPIN (2475 3500) BN 6
J 0
(2463 3508);
DISPLAY 0.680851 (2463 3508);
PAINT GREEN (2463 3508);
FORCEPROP 2 LAST CDS_LIB standard
J 0
(2525 3500);
DISPLAY INVISIBLE (2525 3500);
FORCEPROP 1 LAST BODY_TYPE PLUMBING
J 0
(2525 3550);
DISPLAY 0.872340 (2525 3550);
PAINT GREEN (2525 3550);
DISPLAY INVISIBLE (2525 3550);
FORCEPROP 1 LAST HDL_TAP TRUE
J 0
(2850 3375);
DISPLAY 0.872340 (2850 3375);
DISPLAY INVISIBLE (2850 3375);
FORCEPROP 1 LAST PATH I161
J 0
(2523 3500);
DISPLAY 0.872340 (2523 3500);
PAINT GREEN (2523 3500);
DISPLAY INVISIBLE (2523 3500);
FORCEADD TAP..1
(2525 3600);
FORCEPROP 3 LASTPIN (2475 3600) SIG_NAME M_A_CPU1_SA_DQS_DP<7>
J 0
(2485 3610);
DISPLAY 0.659574 (2485 3610);
PAINT MONO (2485 3610);
DISPLAY INVISIBLE (2485 3610);
FORCEPROP 1 LASTPIN (2475 3600) BN 7
J 0
(2463 3608);
DISPLAY 0.680851 (2463 3608);
PAINT GREEN (2463 3608);
FORCEPROP 2 LAST CDS_LIB standard
J 0
(2525 3600);
DISPLAY INVISIBLE (2525 3600);
FORCEPROP 1 LAST BODY_TYPE PLUMBING
J 0
(2525 3650);
DISPLAY 0.872340 (2525 3650);
PAINT GREEN (2525 3650);
DISPLAY INVISIBLE (2525 3650);
FORCEPROP 1 LAST HDL_TAP TRUE
J 0
(2850 3475);
DISPLAY 0.872340 (2850 3475);
DISPLAY INVISIBLE (2850 3475);
FORCEPROP 1 LAST PATH I162
J 0
(2523 3600);
DISPLAY 0.872340 (2523 3600);
PAINT GREEN (2523 3600);
DISPLAY INVISIBLE (2523 3600);
FORCEADD TAP..1
(2700 3450);
FORCEPROP 3 LASTPIN (2650 3450) SIG_NAME M_A_CPU1_SA_DQS_DN<6>
J 0
(2660 3460);
DISPLAY 0.659574 (2660 3460);
PAINT MONO (2660 3460);
DISPLAY INVISIBLE (2660 3460);
FORCEPROP 1 LASTPIN (2650 3450) BN 6
J 0
(2638 3458);
DISPLAY 0.680851 (2638 3458);
PAINT GREEN (2638 3458);
FORCEPROP 2 LAST CDS_LIB standard
J 0
(2700 3450);
DISPLAY INVISIBLE (2700 3450);
FORCEPROP 1 LAST BODY_TYPE PLUMBING
J 0
(2700 3500);
DISPLAY 0.872340 (2700 3500);
PAINT GREEN (2700 3500);
DISPLAY INVISIBLE (2700 3500);
FORCEPROP 1 LAST HDL_TAP TRUE
J 0
(3025 3325);
DISPLAY 0.872340 (3025 3325);
DISPLAY INVISIBLE (3025 3325);
FORCEPROP 1 LAST PATH I163
J 0
(2698 3450);
DISPLAY 0.872340 (2698 3450);
PAINT GREEN (2698 3450);
DISPLAY INVISIBLE (2698 3450);
FORCEADD TAP..1
(2700 3550);
FORCEPROP 3 LASTPIN (2650 3550) SIG_NAME M_A_CPU1_SA_DQS_DN<7>
J 0
(2660 3560);
DISPLAY 0.659574 (2660 3560);
PAINT MONO (2660 3560);
DISPLAY INVISIBLE (2660 3560);
FORCEPROP 1 LASTPIN (2650 3550) BN 7
J 0
(2638 3558);
DISPLAY 0.680851 (2638 3558);
PAINT GREEN (2638 3558);
FORCEPROP 2 LAST CDS_LIB standard
J 0
(2700 3550);
DISPLAY INVISIBLE (2700 3550);
FORCEPROP 1 LAST BODY_TYPE PLUMBING
J 0
(2700 3600);
DISPLAY 0.872340 (2700 3600);
PAINT GREEN (2700 3600);
DISPLAY INVISIBLE (2700 3600);
FORCEPROP 1 LAST HDL_TAP TRUE
J 0
(3025 3425);
DISPLAY 0.872340 (3025 3425);
DISPLAY INVISIBLE (3025 3425);
FORCEPROP 1 LAST PATH I164
J 0
(2698 3550);
DISPLAY 0.872340 (2698 3550);
PAINT GREEN (2698 3550);
DISPLAY INVISIBLE (2698 3550);
FORCEADD TAP..1
(2700 3650);
FORCEPROP 3 LASTPIN (2650 3650) SIG_NAME M_A_CPU1_SA_DQS_DN<8>
J 0
(2660 3660);
DISPLAY 0.659574 (2660 3660);
PAINT MONO (2660 3660);
DISPLAY INVISIBLE (2660 3660);
FORCEPROP 1 LASTPIN (2650 3650) BN 8
J 0
(2638 3658);
DISPLAY 0.680851 (2638 3658);
PAINT GREEN (2638 3658);
FORCEPROP 2 LAST CDS_LIB standard
J 0
(2700 3650);
DISPLAY INVISIBLE (2700 3650);
FORCEPROP 1 LAST BODY_TYPE PLUMBING
J 0
(2700 3700);
DISPLAY 0.872340 (2700 3700);
PAINT GREEN (2700 3700);
DISPLAY INVISIBLE (2700 3700);
FORCEPROP 1 LAST HDL_TAP TRUE
J 0
(3025 3525);
DISPLAY 0.872340 (3025 3525);
DISPLAY INVISIBLE (3025 3525);
FORCEPROP 1 LAST PATH I165
J 0
(2698 3650);
DISPLAY 0.872340 (2698 3650);
PAINT GREEN (2698 3650);
DISPLAY INVISIBLE (2698 3650);
FORCEADD OFFPAGE..2
(3650 2775);
FORCEPROP 2 LAST $XR1 98 
J 0
(3929 2775);
DISPLAY 0.638298 (3929 2775);
PAINT MONO (3929 2775);
FORCEPROP 2 LAST $XR0 51 
J 0
(3839 2775);
DISPLAY 0.638298 (3839 2775);
PAINT MONO (3839 2775);
FORCEPROP 2 LAST CDS_LIB standard
J 0
(3650 2775);
PAINT MONO (3650 2775);
DISPLAY INVISIBLE (3650 2775);
FORCEPROP 1 LAST OFFPAGE TRUE
J 0
(3975 2650);
DISPLAY 1.170213 (3975 2650);
PAINT GREEN (3975 2650);
DISPLAY INVISIBLE (3975 2650);
FORCEPROP 1 LAST COMMENT_BODY TRUE
J 0
(3605 2680);
DISPLAY 1.170213 (3605 2680);
PAINT GREEN (3605 2680);
DISPLAY INVISIBLE (3605 2680);
FORCEPROP 2 LAST PATH I166
J 0
(3825 2850);
DISPLAY 1.021277 (3825 2850);
DISPLAY INVISIBLE (3825 2850);
FORCEADD OFFPAGE..2
(3650 2725);
FORCEPROP 2 LAST $XR1 98 
J 0
(3929 2725);
DISPLAY 0.638298 (3929 2725);
PAINT MONO (3929 2725);
FORCEPROP 2 LAST $XR0 51 
J 0
(3839 2725);
DISPLAY 0.638298 (3839 2725);
PAINT MONO (3839 2725);
FORCEPROP 2 LAST CDS_LIB standard
J 0
(3650 2725);
PAINT MONO (3650 2725);
DISPLAY INVISIBLE (3650 2725);
FORCEPROP 1 LAST OFFPAGE TRUE
J 0
(3975 2600);
DISPLAY 1.170213 (3975 2600);
PAINT GREEN (3975 2600);
DISPLAY INVISIBLE (3975 2600);
FORCEPROP 1 LAST COMMENT_BODY TRUE
J 0
(3605 2630);
DISPLAY 1.170213 (3605 2630);
PAINT GREEN (3605 2630);
DISPLAY INVISIBLE (3605 2630);
FORCEPROP 2 LAST PATH I167
J 0
(3825 2800);
DISPLAY 1.021277 (3825 2800);
DISPLAY INVISIBLE (3825 2800);
FORCEADD OFFPAGE..3
(600 3825);
FORCEPROP 2 LAST $XR1 98 
J 0
(904 3825);
DISPLAY 0.638298 (904 3825);
PAINT MONO (904 3825);
FORCEPROP 2 LAST $XR0 51 
J 0
(814 3825);
DISPLAY 0.638298 (814 3825);
PAINT MONO (814 3825);
FORCEPROP 2 LAST CDS_LIB standard
J 2
(600 3825);
DISPLAY INVISIBLE (600 3825);
FORCEPROP 1 LAST OFFPAGE TRUE
J 0
(925 3700);
DISPLAY 0.872340 (925 3700);
DISPLAY INVISIBLE (925 3700);
FORCEPROP 1 LAST COMMENT_BODY TRUE
J 0
(550 3725);
DISPLAY 0.872340 (550 3725);
PAINT GREEN (550 3725);
DISPLAY INVISIBLE (550 3725);
FORCEPROP 2 LAST PATH I168
J 0
(800 3900);
DISPLAY 1.021277 (800 3900);
DISPLAY INVISIBLE (800 3900);
FORCEADD TAP..1
(2525 3800);
FORCEPROP 3 LASTPIN (2475 3800) SIG_NAME M_A_CPU1_SA_DQS_DP<9>
J 0
(2485 3810);
DISPLAY 0.659574 (2485 3810);
PAINT MONO (2485 3810);
DISPLAY INVISIBLE (2485 3810);
FORCEPROP 1 LASTPIN (2475 3800) BN 9
J 0
(2463 3808);
DISPLAY 0.680851 (2463 3808);
PAINT GREEN (2463 3808);
FORCEPROP 2 LAST CDS_LIB standard
J 0
(2525 3800);
DISPLAY INVISIBLE (2525 3800);
FORCEPROP 1 LAST BODY_TYPE PLUMBING
J 0
(2525 3850);
DISPLAY 0.872340 (2525 3850);
PAINT GREEN (2525 3850);
DISPLAY INVISIBLE (2525 3850);
FORCEPROP 1 LAST HDL_TAP TRUE
J 0
(2850 3675);
DISPLAY 0.872340 (2850 3675);
DISPLAY INVISIBLE (2850 3675);
FORCEPROP 1 LAST PATH I169
J 0
(2523 3800);
DISPLAY 0.872340 (2523 3800);
PAINT GREEN (2523 3800);
DISPLAY INVISIBLE (2523 3800);
FORCEADD OFFPAGE..1
(-2800 2650);
FORCEPROP 2 LAST $XR0 51 
J 0
(-3021 2650);
DISPLAY 0.638298 (-3021 2650);
PAINT MONO (-3021 2650);
FORCEPROP 2 LAST CDS_LIB standard
J 0
(-2800 2650);
PAINT MONO (-2800 2650);
DISPLAY INVISIBLE (-2800 2650);
FORCEPROP 1 LAST OFFPAGE TRUE
J 0
(-2475 2525);
DISPLAY 0.872340 (-2475 2525);
DISPLAY INVISIBLE (-2475 2525);
FORCEPROP 1 LAST COMMENT_BODY TRUE
J 0
(-2675 2550);
DISPLAY 0.872340 (-2675 2550);
PAINT GREEN (-2675 2550);
DISPLAY INVISIBLE (-2675 2550);
FORCEPROP 2 LAST PATH I17
J 0
(-2750 2725);
DISPLAY 1.021277 (-2750 2725);
DISPLAY INVISIBLE (-2750 2725);
FORCEADD TAP..1
(2525 3700);
FORCEPROP 3 LASTPIN (2475 3700) SIG_NAME M_A_CPU1_SA_DQS_DP<8>
J 0
(2485 3710);
DISPLAY 0.659574 (2485 3710);
PAINT MONO (2485 3710);
DISPLAY INVISIBLE (2485 3710);
FORCEPROP 1 LASTPIN (2475 3700) BN 8
J 0
(2463 3708);
DISPLAY 0.680851 (2463 3708);
PAINT GREEN (2463 3708);
FORCEPROP 2 LAST CDS_LIB standard
J 0
(2525 3700);
DISPLAY INVISIBLE (2525 3700);
FORCEPROP 1 LAST BODY_TYPE PLUMBING
J 0
(2525 3750);
DISPLAY 0.872340 (2525 3750);
PAINT GREEN (2525 3750);
DISPLAY INVISIBLE (2525 3750);
FORCEPROP 1 LAST HDL_TAP TRUE
J 0
(2850 3575);
DISPLAY 0.872340 (2850 3575);
DISPLAY INVISIBLE (2850 3575);
FORCEPROP 1 LAST PATH I170
J 0
(2523 3700);
DISPLAY 0.872340 (2523 3700);
PAINT GREEN (2523 3700);
DISPLAY INVISIBLE (2523 3700);
FORCEADD TAP..1
(2700 3750);
FORCEPROP 3 LASTPIN (2650 3750) SIG_NAME M_A_CPU1_SA_DQS_DN<9>
J 0
(2660 3760);
DISPLAY 0.659574 (2660 3760);
PAINT MONO (2660 3760);
DISPLAY INVISIBLE (2660 3760);
FORCEPROP 1 LASTPIN (2650 3750) BN 9
J 0
(2638 3758);
DISPLAY 0.680851 (2638 3758);
PAINT GREEN (2638 3758);
FORCEPROP 2 LAST CDS_LIB standard
J 0
(2700 3750);
DISPLAY INVISIBLE (2700 3750);
FORCEPROP 1 LAST BODY_TYPE PLUMBING
J 0
(2700 3800);
DISPLAY 0.872340 (2700 3800);
PAINT GREEN (2700 3800);
DISPLAY INVISIBLE (2700 3800);
FORCEPROP 1 LAST HDL_TAP TRUE
J 0
(3025 3625);
DISPLAY 0.872340 (3025 3625);
DISPLAY INVISIBLE (3025 3625);
FORCEPROP 1 LAST PATH I171
J 0
(2698 3750);
DISPLAY 0.872340 (2698 3750);
PAINT GREEN (2698 3750);
DISPLAY INVISIBLE (2698 3750);
FORCEADD OFFPAGE..2
(3650 3825);
FORCEPROP 2 LAST $XR1 98 
J 0
(3929 3825);
DISPLAY 0.638298 (3929 3825);
PAINT MONO (3929 3825);
FORCEPROP 2 LAST $XR0 51 
J 0
(3839 3825);
DISPLAY 0.638298 (3839 3825);
PAINT MONO (3839 3825);
FORCEPROP 2 LAST CDS_LIB standard
J 0
(3650 3825);
PAINT MONO (3650 3825);
DISPLAY INVISIBLE (3650 3825);
FORCEPROP 1 LAST OFFPAGE TRUE
J 0
(3975 3700);
DISPLAY 1.170213 (3975 3700);
PAINT GREEN (3975 3700);
DISPLAY INVISIBLE (3975 3700);
FORCEPROP 1 LAST COMMENT_BODY TRUE
J 0
(3605 3730);
DISPLAY 1.170213 (3605 3730);
PAINT GREEN (3605 3730);
DISPLAY INVISIBLE (3605 3730);
FORCEPROP 2 LAST PATH I172
J 0
(3825 3900);
DISPLAY 1.021277 (3825 3900);
DISPLAY INVISIBLE (3825 3900);
FORCEADD OFFPAGE..2
(3650 3775);
FORCEPROP 2 LAST $XR1 98 
J 0
(3929 3775);
DISPLAY 0.638298 (3929 3775);
PAINT MONO (3929 3775);
FORCEPROP 2 LAST $XR0 51 
J 0
(3839 3775);
DISPLAY 0.638298 (3839 3775);
PAINT MONO (3839 3775);
FORCEPROP 2 LAST CDS_LIB standard
J 0
(3650 3775);
PAINT MONO (3650 3775);
DISPLAY INVISIBLE (3650 3775);
FORCEPROP 1 LAST OFFPAGE TRUE
J 0
(3975 3650);
DISPLAY 1.170213 (3975 3650);
PAINT GREEN (3975 3650);
DISPLAY INVISIBLE (3975 3650);
FORCEPROP 1 LAST COMMENT_BODY TRUE
J 0
(3605 3680);
DISPLAY 1.170213 (3605 3680);
PAINT GREEN (3605 3680);
DISPLAY INVISIBLE (3605 3680);
FORCEPROP 2 LAST PATH I173
J 0
(3825 3850);
DISPLAY 1.021277 (3825 3850);
DISPLAY INVISIBLE (3825 3850);
FORCEADD UNIVERSAL_GND..1
(4200 100);
FORCEPROP 3 LASTPIN (4200 150) SIG_NAME GND\g
J 0
(4210 160);
DISPLAY 0.659574 (4210 160);
PAINT MONO (4210 160);
DISPLAY INVISIBLE (4210 160);
FORCEPROP 1 LAST PATH I174
J 0
(4275 100);
DISPLAY 0.872340 (4275 100);
PAINT AQUA (4275 100);
DISPLAY INVISIBLE (4275 100);
FORCEPROP 1 LAST HDL_POWER GND
J 1
(4225 25);
DISPLAY 0.872340 (4225 25);
PAINT GREEN (4225 25);
DISPLAY INVISIBLE (4225 25);
FORCEPROP 2 LAST CDS_LIB logical_power
J 0
(4200 100);
PAINT MONO (4200 100);
DISPLAY INVISIBLE (4200 100);
FORCEADD SCONN288_ADR50017P087CC..3
(5050 2175);
FORCEPROP 1 LAST PART_NUMBER DFHST8FS460
J 0
(4595 4099);
DISPLAY 0.723404 (4595 4099);
PAINT GREEN (4595 4099);
DISPLAY INVISIBLE (4595 4099);
FORCEPROP 1 LAST MATERIAL IO
J 0
(4595 3972);
DISPLAY 0.723404 (4595 3972);
PAINT GREEN (4595 3972);
FORCEPROP 2 LAST VALUE SCONN288_ADR50017-P087CC
J 0
(4600 4200);
DISPLAY 1.021277 (4600 4200);
FORCEPROP 2 LAST PART_TYPE SMLF
J 0
(4600 4250);
DISPLAY 1.021277 (4600 4250);
FORCEPROP 1 LAST $LOCATION J18
J 0
(4600 4150);
DISPLAY 0.723404 (4600 4150);
PAINT GREEN (4600 4150);
FORCEPROP 0 LASTPIN (5650 550) $PN G1
J 0
(5660 560);
DISPLAY 0.680851 (5660 560);
PAINT MONO (5660 560);
FORCEPROP 0 LASTPIN (5650 500) $PN G2
J 0
(5660 510);
DISPLAY 0.680851 (5660 510);
PAINT MONO (5660 510);
FORCEPROP 0 LASTPIN (5650 450) $PN G3
J 0
(5660 460);
DISPLAY 0.680851 (5660 460);
PAINT MONO (5660 460);
FORCEPROP 0 LASTPIN (4450 3700) $PN 1
J 2
(4440 3710);
DISPLAY 0.680851 (4440 3710);
PAINT MONO (4440 3710);
FORCEPROP 0 LASTPIN (4450 3750) $PN 145
J 2
(4440 3760);
DISPLAY 0.680851 (4440 3760);
PAINT MONO (4440 3760);
FORCEPROP 0 LASTPIN (4450 3800) $PN 146
J 2
(4440 3810);
DISPLAY 0.680851 (4440 3810);
PAINT MONO (4440 3810);
FORCEPROP 0 LASTPIN (5650 650) $PN 6
J 0
(5660 660);
DISPLAY 0.680851 (5660 660);
PAINT MONO (5660 660);
FORCEPROP 0 LASTPIN (5650 700) $PN 8
J 0
(5660 710);
DISPLAY 0.680851 (5660 710);
PAINT MONO (5660 710);
FORCEPROP 0 LASTPIN (5650 750) $PN 10
J 0
(5660 760);
DISPLAY 0.680851 (5660 760);
PAINT MONO (5660 760);
FORCEPROP 0 LASTPIN (5650 800) $PN 13
J 0
(5660 810);
DISPLAY 0.680851 (5660 810);
PAINT MONO (5660 810);
FORCEPROP 0 LASTPIN (5650 850) $PN 15
J 0
(5660 860);
DISPLAY 0.680851 (5660 860);
PAINT MONO (5660 860);
FORCEPROP 0 LASTPIN (5650 900) $PN 17
J 0
(5660 910);
DISPLAY 0.680851 (5660 910);
PAINT MONO (5660 910);
FORCEPROP 0 LASTPIN (5650 950) $PN 19
J 0
(5660 960);
DISPLAY 0.680851 (5660 960);
PAINT MONO (5660 960);
FORCEPROP 0 LASTPIN (5650 1000) $PN 21
J 0
(5660 1010);
DISPLAY 0.680851 (5660 1010);
PAINT MONO (5660 1010);
FORCEPROP 0 LASTPIN (5650 1050) $PN 24
J 0
(5660 1060);
DISPLAY 0.680851 (5660 1060);
PAINT MONO (5660 1060);
FORCEPROP 0 LASTPIN (5650 1100) $PN 26
J 0
(5660 1110);
DISPLAY 0.680851 (5660 1110);
PAINT MONO (5660 1110);
FORCEPROP 0 LASTPIN (5650 1150) $PN 28
J 0
(5660 1160);
DISPLAY 0.680851 (5660 1160);
PAINT MONO (5660 1160);
FORCEPROP 0 LASTPIN (5650 1200) $PN 30
J 0
(5660 1210);
DISPLAY 0.680851 (5660 1210);
PAINT MONO (5660 1210);
FORCEPROP 0 LASTPIN (5650 1250) $PN 32
J 0
(5660 1260);
DISPLAY 0.680851 (5660 1260);
PAINT MONO (5660 1260);
FORCEPROP 0 LASTPIN (5650 1300) $PN 35
J 0
(5660 1310);
DISPLAY 0.680851 (5660 1310);
PAINT MONO (5660 1310);
FORCEPROP 0 LASTPIN (5650 1350) $PN 37
J 0
(5660 1360);
DISPLAY 0.680851 (5660 1360);
PAINT MONO (5660 1360);
FORCEPROP 0 LASTPIN (5650 1400) $PN 39
J 0
(5660 1410);
DISPLAY 0.680851 (5660 1410);
PAINT MONO (5660 1410);
FORCEPROP 0 LASTPIN (5650 1450) $PN 41
J 0
(5660 1460);
DISPLAY 0.680851 (5660 1460);
PAINT MONO (5660 1460);
FORCEPROP 0 LASTPIN (5650 1500) $PN 43
J 0
(5660 1510);
DISPLAY 0.680851 (5660 1510);
PAINT MONO (5660 1510);
FORCEPROP 0 LASTPIN (5650 1550) $PN 46
J 0
(5660 1560);
DISPLAY 0.680851 (5660 1560);
PAINT MONO (5660 1560);
FORCEPROP 0 LASTPIN (5650 1600) $PN 48
J 0
(5660 1610);
DISPLAY 0.680851 (5660 1610);
PAINT MONO (5660 1610);
FORCEPROP 0 LASTPIN (5650 1650) $PN 50
J 0
(5660 1660);
DISPLAY 0.680851 (5660 1660);
PAINT MONO (5660 1660);
FORCEPROP 0 LASTPIN (5650 1700) $PN 52
J 0
(5660 1710);
DISPLAY 0.680851 (5660 1710);
PAINT MONO (5660 1710);
FORCEPROP 0 LASTPIN (5650 1750) $PN 54
J 0
(5660 1760);
DISPLAY 0.680851 (5660 1760);
PAINT MONO (5660 1760);
FORCEPROP 0 LASTPIN (5650 1800) $PN 57
J 0
(5660 1810);
DISPLAY 0.680851 (5660 1810);
PAINT MONO (5660 1810);
FORCEPROP 0 LASTPIN (5650 1850) $PN 59
J 0
(5660 1860);
DISPLAY 0.680851 (5660 1860);
PAINT MONO (5660 1860);
FORCEPROP 0 LASTPIN (5650 1900) $PN 61
J 0
(5660 1910);
DISPLAY 0.680851 (5660 1910);
PAINT MONO (5660 1910);
FORCEPROP 0 LASTPIN (5650 1950) $PN 63
J 0
(5660 1960);
DISPLAY 0.680851 (5660 1960);
PAINT MONO (5660 1960);
FORCEPROP 0 LASTPIN (5650 2000) $PN 65
J 0
(5660 2010);
DISPLAY 0.680851 (5660 2010);
PAINT MONO (5660 2010);
FORCEPROP 0 LASTPIN (5650 2050) $PN 67
J 0
(5660 2060);
DISPLAY 0.680851 (5660 2060);
PAINT MONO (5660 2060);
FORCEPROP 0 LASTPIN (5650 2100) $PN 69
J 0
(5660 2110);
DISPLAY 0.680851 (5660 2110);
PAINT MONO (5660 2110);
FORCEPROP 0 LASTPIN (5650 2150) $PN 71
J 0
(5660 2160);
DISPLAY 0.680851 (5660 2160);
PAINT MONO (5660 2160);
FORCEPROP 0 LASTPIN (5650 2200) $PN 73
J 0
(5660 2210);
DISPLAY 0.680851 (5660 2210);
PAINT MONO (5660 2210);
FORCEPROP 0 LASTPIN (5650 2250) $PN 75
J 0
(5660 2260);
DISPLAY 0.680851 (5660 2260);
PAINT MONO (5660 2260);
FORCEPROP 0 LASTPIN (5650 2300) $PN 77
J 0
(5660 2310);
DISPLAY 0.680851 (5660 2310);
PAINT MONO (5660 2310);
FORCEPROP 0 LASTPIN (5650 2350) $PN 79
J 0
(5660 2360);
DISPLAY 0.680851 (5660 2360);
PAINT MONO (5660 2360);
FORCEPROP 0 LASTPIN (5650 2400) $PN 81
J 0
(5660 2410);
DISPLAY 0.680851 (5660 2410);
PAINT MONO (5660 2410);
FORCEPROP 0 LASTPIN (5650 2450) $PN 83
J 0
(5660 2460);
DISPLAY 0.680851 (5660 2460);
PAINT MONO (5660 2460);
FORCEPROP 0 LASTPIN (5650 2500) $PN 85
J 0
(5660 2510);
DISPLAY 0.680851 (5660 2510);
PAINT MONO (5660 2510);
FORCEPROP 0 LASTPIN (5650 2550) $PN 88
J 0
(5660 2560);
DISPLAY 0.680851 (5660 2560);
PAINT MONO (5660 2560);
FORCEPROP 0 LASTPIN (5650 2600) $PN 90
J 0
(5660 2610);
DISPLAY 0.680851 (5660 2610);
PAINT MONO (5660 2610);
FORCEPROP 0 LASTPIN (5650 2650) $PN 92
J 0
(5660 2660);
DISPLAY 0.680851 (5660 2660);
PAINT MONO (5660 2660);
FORCEPROP 0 LASTPIN (5650 2700) $PN 95
J 0
(5660 2710);
DISPLAY 0.680851 (5660 2710);
PAINT MONO (5660 2710);
FORCEPROP 0 LASTPIN (5650 2750) $PN 97
J 0
(5660 2760);
DISPLAY 0.680851 (5660 2760);
PAINT MONO (5660 2760);
FORCEPROP 0 LASTPIN (5650 2800) $PN 99
J 0
(5660 2810);
DISPLAY 0.680851 (5660 2810);
PAINT MONO (5660 2810);
FORCEPROP 0 LASTPIN (5650 2850) $PN 101
J 0
(5660 2860);
DISPLAY 0.680851 (5660 2860);
PAINT MONO (5660 2860);
FORCEPROP 0 LASTPIN (5650 2900) $PN 103
J 0
(5660 2910);
DISPLAY 0.680851 (5660 2910);
PAINT MONO (5660 2910);
FORCEPROP 0 LASTPIN (5650 2950) $PN 106
J 0
(5660 2960);
DISPLAY 0.680851 (5660 2960);
PAINT MONO (5660 2960);
FORCEPROP 0 LASTPIN (5650 3000) $PN 108
J 0
(5660 3010);
DISPLAY 0.680851 (5660 3010);
PAINT MONO (5660 3010);
FORCEPROP 0 LASTPIN (5650 3050) $PN 110
J 0
(5660 3060);
DISPLAY 0.680851 (5660 3060);
PAINT MONO (5660 3060);
FORCEPROP 0 LASTPIN (5650 3100) $PN 112
J 0
(5660 3110);
DISPLAY 0.680851 (5660 3110);
PAINT MONO (5660 3110);
FORCEPROP 0 LASTPIN (5650 3150) $PN 114
J 0
(5660 3160);
DISPLAY 0.680851 (5660 3160);
PAINT MONO (5660 3160);
FORCEPROP 0 LASTPIN (5650 3200) $PN 117
J 0
(5660 3210);
DISPLAY 0.680851 (5660 3210);
PAINT MONO (5660 3210);
FORCEPROP 0 LASTPIN (5650 3250) $PN 119
J 0
(5660 3260);
DISPLAY 0.680851 (5660 3260);
PAINT MONO (5660 3260);
FORCEPROP 0 LASTPIN (5650 3300) $PN 121
J 0
(5660 3310);
DISPLAY 0.680851 (5660 3310);
PAINT MONO (5660 3310);
FORCEPROP 0 LASTPIN (5650 3350) $PN 123
J 0
(5660 3360);
DISPLAY 0.680851 (5660 3360);
PAINT MONO (5660 3360);
FORCEPROP 0 LASTPIN (5650 3400) $PN 125
J 0
(5660 3410);
DISPLAY 0.680851 (5660 3410);
PAINT MONO (5660 3410);
FORCEPROP 0 LASTPIN (5650 3450) $PN 128
J 0
(5660 3460);
DISPLAY 0.680851 (5660 3460);
PAINT MONO (5660 3460);
FORCEPROP 0 LASTPIN (5650 3500) $PN 130
J 0
(5660 3510);
DISPLAY 0.680851 (5660 3510);
PAINT MONO (5660 3510);
FORCEPROP 0 LASTPIN (5650 3550) $PN 132
J 0
(5660 3560);
DISPLAY 0.680851 (5660 3560);
PAINT MONO (5660 3560);
FORCEPROP 0 LASTPIN (5650 3600) $PN 134
J 0
(5660 3610);
DISPLAY 0.680851 (5660 3610);
PAINT MONO (5660 3610);
FORCEPROP 0 LASTPIN (5650 3650) $PN 136
J 0
(5660 3660);
DISPLAY 0.680851 (5660 3660);
PAINT MONO (5660 3660);
FORCEPROP 0 LASTPIN (5650 3700) $PN 139
J 0
(5660 3710);
DISPLAY 0.680851 (5660 3710);
PAINT MONO (5660 3710);
FORCEPROP 0 LASTPIN (5650 3750) $PN 141
J 0
(5660 3760);
DISPLAY 0.680851 (5660 3760);
PAINT MONO (5660 3760);
FORCEPROP 0 LASTPIN (5650 3800) $PN 143
J 0
(5660 3810);
DISPLAY 0.680851 (5660 3810);
PAINT MONO (5660 3810);
FORCEPROP 0 LASTPIN (4450 550) $PN 151
J 2
(4440 560);
DISPLAY 0.680851 (4440 560);
PAINT MONO (4440 560);
FORCEPROP 0 LASTPIN (4450 600) $PN 153
J 2
(4440 610);
DISPLAY 0.680851 (4440 610);
PAINT MONO (4440 610);
FORCEPROP 0 LASTPIN (4450 650) $PN 155
J 2
(4440 660);
DISPLAY 0.680851 (4440 660);
PAINT MONO (4440 660);
FORCEPROP 0 LASTPIN (4450 700) $PN 158
J 2
(4440 710);
DISPLAY 0.680851 (4440 710);
PAINT MONO (4440 710);
FORCEPROP 0 LASTPIN (4450 750) $PN 160
J 2
(4440 760);
DISPLAY 0.680851 (4440 760);
PAINT MONO (4440 760);
FORCEPROP 0 LASTPIN (4450 800) $PN 162
J 2
(4440 810);
DISPLAY 0.680851 (4440 810);
PAINT MONO (4440 810);
FORCEPROP 0 LASTPIN (4450 850) $PN 164
J 2
(4440 860);
DISPLAY 0.680851 (4440 860);
PAINT MONO (4440 860);
FORCEPROP 0 LASTPIN (4450 900) $PN 166
J 2
(4440 910);
DISPLAY 0.680851 (4440 910);
PAINT MONO (4440 910);
FORCEPROP 0 LASTPIN (4450 950) $PN 169
J 2
(4440 960);
DISPLAY 0.680851 (4440 960);
PAINT MONO (4440 960);
FORCEPROP 0 LASTPIN (4450 1000) $PN 171
J 2
(4440 1010);
DISPLAY 0.680851 (4440 1010);
PAINT MONO (4440 1010);
FORCEPROP 0 LASTPIN (4450 1050) $PN 173
J 2
(4440 1060);
DISPLAY 0.680851 (4440 1060);
PAINT MONO (4440 1060);
FORCEPROP 0 LASTPIN (4450 1100) $PN 175
J 2
(4440 1110);
DISPLAY 0.680851 (4440 1110);
PAINT MONO (4440 1110);
FORCEPROP 0 LASTPIN (4450 1150) $PN 177
J 2
(4440 1160);
DISPLAY 0.680851 (4440 1160);
PAINT MONO (4440 1160);
FORCEPROP 0 LASTPIN (4450 1200) $PN 180
J 2
(4440 1210);
DISPLAY 0.680851 (4440 1210);
PAINT MONO (4440 1210);
FORCEPROP 0 LASTPIN (4450 1250) $PN 182
J 2
(4440 1260);
DISPLAY 0.680851 (4440 1260);
PAINT MONO (4440 1260);
FORCEPROP 0 LASTPIN (4450 1300) $PN 184
J 2
(4440 1310);
DISPLAY 0.680851 (4440 1310);
PAINT MONO (4440 1310);
FORCEPROP 0 LASTPIN (4450 1350) $PN 186
J 2
(4440 1360);
DISPLAY 0.680851 (4440 1360);
PAINT MONO (4440 1360);
FORCEPROP 0 LASTPIN (4450 1400) $PN 188
J 2
(4440 1410);
DISPLAY 0.680851 (4440 1410);
PAINT MONO (4440 1410);
FORCEPROP 0 LASTPIN (4450 1450) $PN 191
J 2
(4440 1460);
DISPLAY 0.680851 (4440 1460);
PAINT MONO (4440 1460);
FORCEPROP 0 LASTPIN (4450 1500) $PN 193
J 2
(4440 1510);
DISPLAY 0.680851 (4440 1510);
PAINT MONO (4440 1510);
FORCEPROP 0 LASTPIN (4450 1550) $PN 195
J 2
(4440 1560);
DISPLAY 0.680851 (4440 1560);
PAINT MONO (4440 1560);
FORCEPROP 0 LASTPIN (4450 1600) $PN 197
J 2
(4440 1610);
DISPLAY 0.680851 (4440 1610);
PAINT MONO (4440 1610);
FORCEPROP 0 LASTPIN (4450 1650) $PN 199
J 2
(4440 1660);
DISPLAY 0.680851 (4440 1660);
PAINT MONO (4440 1660);
FORCEPROP 0 LASTPIN (4450 1700) $PN 202
J 2
(4440 1710);
DISPLAY 0.680851 (4440 1710);
PAINT MONO (4440 1710);
FORCEPROP 0 LASTPIN (4450 1750) $PN 204
J 2
(4440 1760);
DISPLAY 0.680851 (4440 1760);
PAINT MONO (4440 1760);
FORCEPROP 0 LASTPIN (4450 1800) $PN 206
J 2
(4440 1810);
DISPLAY 0.680851 (4440 1810);
PAINT MONO (4440 1810);
FORCEPROP 0 LASTPIN (4450 1850) $PN 208
J 2
(4440 1860);
DISPLAY 0.680851 (4440 1860);
PAINT MONO (4440 1860);
FORCEPROP 0 LASTPIN (4450 1900) $PN 210
J 2
(4440 1910);
DISPLAY 0.680851 (4440 1910);
PAINT MONO (4440 1910);
FORCEPROP 0 LASTPIN (4450 1950) $PN 212
J 2
(4440 1960);
DISPLAY 0.680851 (4440 1960);
PAINT MONO (4440 1960);
FORCEPROP 0 LASTPIN (4450 2000) $PN 214
J 2
(4440 2010);
DISPLAY 0.680851 (4440 2010);
PAINT MONO (4440 2010);
FORCEPROP 0 LASTPIN (4450 2050) $PN 216
J 2
(4440 2060);
DISPLAY 0.680851 (4440 2060);
PAINT MONO (4440 2060);
FORCEPROP 0 LASTPIN (4450 2100) $PN 219
J 2
(4440 2110);
DISPLAY 0.680851 (4440 2110);
PAINT MONO (4440 2110);
FORCEPROP 0 LASTPIN (4450 2150) $PN 222
J 2
(4440 2160);
DISPLAY 0.680851 (4440 2160);
PAINT MONO (4440 2160);
FORCEPROP 0 LASTPIN (4450 2200) $PN 224
J 2
(4440 2210);
DISPLAY 0.680851 (4440 2210);
PAINT MONO (4440 2210);
FORCEPROP 0 LASTPIN (4450 2250) $PN 226
J 2
(4440 2260);
DISPLAY 0.680851 (4440 2260);
PAINT MONO (4440 2260);
FORCEPROP 0 LASTPIN (4450 2300) $PN 228
J 2
(4440 2310);
DISPLAY 0.680851 (4440 2310);
PAINT MONO (4440 2310);
FORCEPROP 0 LASTPIN (4450 2350) $PN 230
J 2
(4440 2360);
DISPLAY 0.680851 (4440 2360);
PAINT MONO (4440 2360);
FORCEPROP 0 LASTPIN (4450 2400) $PN 233
J 2
(4440 2410);
DISPLAY 0.680851 (4440 2410);
PAINT MONO (4440 2410);
FORCEPROP 0 LASTPIN (4450 2450) $PN 235
J 2
(4440 2460);
DISPLAY 0.680851 (4440 2460);
PAINT MONO (4440 2460);
FORCEPROP 0 LASTPIN (4450 2500) $PN 237
J 2
(4440 2510);
DISPLAY 0.680851 (4440 2510);
PAINT MONO (4440 2510);
FORCEPROP 0 LASTPIN (4450 2550) $PN 240
J 2
(4440 2560);
DISPLAY 0.680851 (4440 2560);
PAINT MONO (4440 2560);
FORCEPROP 0 LASTPIN (4450 2600) $PN 242
J 2
(4440 2610);
DISPLAY 0.680851 (4440 2610);
PAINT MONO (4440 2610);
FORCEPROP 0 LASTPIN (4450 2650) $PN 244
J 2
(4440 2660);
DISPLAY 0.680851 (4440 2660);
PAINT MONO (4440 2660);
FORCEPROP 0 LASTPIN (4450 2700) $PN 246
J 2
(4440 2710);
DISPLAY 0.680851 (4440 2710);
PAINT MONO (4440 2710);
FORCEPROP 0 LASTPIN (4450 2750) $PN 248
J 2
(4440 2760);
DISPLAY 0.680851 (4440 2760);
PAINT MONO (4440 2760);
FORCEPROP 0 LASTPIN (4450 2800) $PN 251
J 2
(4440 2810);
DISPLAY 0.680851 (4440 2810);
PAINT MONO (4440 2810);
FORCEPROP 0 LASTPIN (4450 2850) $PN 253
J 2
(4440 2860);
DISPLAY 0.680851 (4440 2860);
PAINT MONO (4440 2860);
FORCEPROP 0 LASTPIN (4450 2900) $PN 255
J 2
(4440 2910);
DISPLAY 0.680851 (4440 2910);
PAINT MONO (4440 2910);
FORCEPROP 0 LASTPIN (4450 2950) $PN 257
J 2
(4440 2960);
DISPLAY 0.680851 (4440 2960);
PAINT MONO (4440 2960);
FORCEPROP 0 LASTPIN (4450 3000) $PN 259
J 2
(4440 3010);
DISPLAY 0.680851 (4440 3010);
PAINT MONO (4440 3010);
FORCEPROP 0 LASTPIN (4450 3050) $PN 262
J 2
(4440 3060);
DISPLAY 0.680851 (4440 3060);
PAINT MONO (4440 3060);
FORCEPROP 0 LASTPIN (4450 3100) $PN 264
J 2
(4440 3110);
DISPLAY 0.680851 (4440 3110);
PAINT MONO (4440 3110);
FORCEPROP 0 LASTPIN (4450 3150) $PN 266
J 2
(4440 3160);
DISPLAY 0.680851 (4440 3160);
PAINT MONO (4440 3160);
FORCEPROP 0 LASTPIN (4450 3200) $PN 268
J 2
(4440 3210);
DISPLAY 0.680851 (4440 3210);
PAINT MONO (4440 3210);
FORCEPROP 0 LASTPIN (4450 3250) $PN 270
J 2
(4440 3260);
DISPLAY 0.680851 (4440 3260);
PAINT MONO (4440 3260);
FORCEPROP 0 LASTPIN (4450 3300) $PN 273
J 2
(4440 3310);
DISPLAY 0.680851 (4440 3310);
PAINT MONO (4440 3310);
FORCEPROP 0 LASTPIN (4450 3350) $PN 275
J 2
(4440 3360);
DISPLAY 0.680851 (4440 3360);
PAINT MONO (4440 3360);
FORCEPROP 0 LASTPIN (4450 3400) $PN 277
J 2
(4440 3410);
DISPLAY 0.680851 (4440 3410);
PAINT MONO (4440 3410);
FORCEPROP 0 LASTPIN (4450 3450) $PN 279
J 2
(4440 3460);
DISPLAY 0.680851 (4440 3460);
PAINT MONO (4440 3460);
FORCEPROP 0 LASTPIN (4450 3500) $PN 281
J 2
(4440 3510);
DISPLAY 0.680851 (4440 3510);
PAINT MONO (4440 3510);
FORCEPROP 0 LASTPIN (4450 3550) $PN 284
J 2
(4440 3560);
DISPLAY 0.680851 (4440 3560);
PAINT MONO (4440 3560);
FORCEPROP 0 LASTPIN (4450 3600) $PN 286
J 2
(4440 3610);
DISPLAY 0.680851 (4440 3610);
PAINT MONO (4440 3610);
FORCEPROP 0 LASTPIN (4450 3650) $PN 288
J 2
(4440 3660);
DISPLAY 0.680851 (4440 3660);
PAINT MONO (4440 3660);
FORCEPROP 2 LAST CDS_LIB pure_quanta
J 0
(5050 2175);
DISPLAY INVISIBLE (5050 2175);
FORCEPROP 1 LAST CDS_LMAN_SYM_OUTLINE -450,1775,450,-1775
J 0
(5050 2175);
DISPLAY 0.468085 (5050 2175);
PAINT GREEN (5050 2175);
DISPLAY INVISIBLE (5050 2175);
FORCEPROP 1 LAST NEEDS_NO_SIZE TRUE
J 0
(5050 2175);
DISPLAY 0.723404 (5050 2175);
PAINT GREEN (5050 2175);
DISPLAY INVISIBLE (5050 2175);
FORCEPROP 1 LAST PATH I175
J 0
(5050 2175);
DISPLAY 0.723404 (5050 2175);
PAINT GREEN (5050 2175);
DISPLAY INVISIBLE (5050 2175);
FORCEPROP 2 LAST CDS_LOCATION J18
J 0
(4600 4300);
DISPLAY 1.021277 (4600 4300);
DISPLAY INVISIBLE (4600 4300);
FORCEPROP 0 LAST $SEC 3
J 0
(4600 4300);
DISPLAY 0.680851 (4600 4300);
PAINT MONO (4600 4300);
DISPLAY INVISIBLE (4600 4300);
FORCEPROP 2 LAST CDS_SEC 3
J 0
(4600 4300);
DISPLAY 1.021277 (4600 4300);
DISPLAY INVISIBLE (4600 4300);
FORCEADD UNIVERSAL_GND..1
(5900 100);
FORCEPROP 3 LASTPIN (5900 150) SIG_NAME GND\g
J 0
(5910 160);
DISPLAY 0.659574 (5910 160);
PAINT MONO (5910 160);
DISPLAY INVISIBLE (5910 160);
FORCEPROP 1 LAST PATH I176
J 0
(5975 100);
DISPLAY 0.872340 (5975 100);
PAINT AQUA (5975 100);
DISPLAY INVISIBLE (5975 100);
FORCEPROP 1 LAST HDL_POWER GND
J 1
(5925 25);
DISPLAY 0.872340 (5925 25);
PAINT GREEN (5925 25);
DISPLAY INVISIBLE (5925 25);
FORCEPROP 2 LAST CDS_LIB logical_power
J 0
(5900 100);
PAINT MONO (5900 100);
DISPLAY INVISIBLE (5900 100);
FORCEADD VCC_CORE..1
(4200 4350);
FORCEPROP 3 LASTPIN (4200 4300) SIG_NAME P12V_S3_AUX_CPU1_NVDIMM\g
J 0
(4210 4310);
DISPLAY 0.659574 (4210 4310);
PAINT MONO (4210 4310);
DISPLAY INVISIBLE (4210 4310);
FORCEPROP 1 LAST HDL_POWER P12V_S3_AUX_CPU1_NVDIMM
J 1
(4200 4400);
DISPLAY 1.148936 (4200 4400);
PAINT GREEN (4200 4400);
FORCEPROP 2 LAST CDS_LIB logical_power
J 0
(4200 4350);
PAINT MONO (4200 4350);
DISPLAY INVISIBLE (4200 4350);
FORCEPROP 1 LAST PATH I177
J 0
(4250 4375);
DISPLAY 0.872340 (4250 4375);
PAINT AQUA (4250 4375);
DISPLAY INVISIBLE (4250 4375);
FORCEADD SCONN288_ADR50017P087CC..2
(1625 2800);
FORCEPROP 1 LAST PART_NUMBER DFHST8FS460
J 0
(1020 4088);
DISPLAY 0.723404 (1020 4088);
PAINT GREEN (1020 4088);
DISPLAY INVISIBLE (1020 4088);
FORCEPROP 2 LAST PART_TYPE SMLF
J 0
(1025 4325);
DISPLAY 1.021277 (1025 4325);
FORCEPROP 2 LAST VALUE SCONN288_ADR50017-P087CC
J 0
(1025 4275);
DISPLAY 1.021277 (1025 4275);
FORCEPROP 1 LAST MATERIAL IO
J 0
(1020 3961);
DISPLAY 0.723404 (1020 3961);
PAINT GREEN (1020 3961);
FORCEPROP 1 LAST LOCATION J18
J 0
(1020 4235);
DISPLAY 0.723404 (1020 4235);
PAINT GREEN (1020 4235);
FORCEPROP 0 LASTPIN (2375 2850) $PN 12
J 0
(2385 2860);
DISPLAY 0.680851 (2385 2860);
PAINT MONO (2385 2860);
FORCEPROP 0 LASTPIN (2375 2900) $PN 11
J 0
(2385 2910);
DISPLAY 0.680851 (2385 2910);
PAINT MONO (2385 2910);
FORCEPROP 0 LASTPIN (2375 1800) $PN 105
J 0
(2385 1810);
DISPLAY 0.680851 (2385 1810);
PAINT MONO (2385 1810);
FORCEPROP 0 LASTPIN (2375 1850) $PN 104
J 0
(2385 1860);
DISPLAY 0.680851 (2385 1860);
PAINT MONO (2385 1860);
FORCEPROP 0 LASTPIN (2375 2950) $PN 23
J 0
(2385 2960);
DISPLAY 0.680851 (2385 2960);
PAINT MONO (2385 2960);
FORCEPROP 0 LASTPIN (2375 3000) $PN 22
J 0
(2385 3010);
DISPLAY 0.680851 (2385 3010);
PAINT MONO (2385 3010);
FORCEPROP 0 LASTPIN (2375 1900) $PN 116
J 0
(2385 1910);
DISPLAY 0.680851 (2385 1910);
PAINT MONO (2385 1910);
FORCEPROP 0 LASTPIN (2375 1950) $PN 115
J 0
(2385 1960);
DISPLAY 0.680851 (2385 1960);
PAINT MONO (2385 1960);
FORCEPROP 0 LASTPIN (2375 3050) $PN 34
J 0
(2385 3060);
DISPLAY 0.680851 (2385 3060);
PAINT MONO (2385 3060);
FORCEPROP 0 LASTPIN (2375 3100) $PN 33
J 0
(2385 3110);
DISPLAY 0.680851 (2385 3110);
PAINT MONO (2385 3110);
FORCEPROP 0 LASTPIN (2375 2000) $PN 127
J 0
(2385 2010);
DISPLAY 0.680851 (2385 2010);
PAINT MONO (2385 2010);
FORCEPROP 0 LASTPIN (2375 2050) $PN 126
J 0
(2385 2060);
DISPLAY 0.680851 (2385 2060);
PAINT MONO (2385 2060);
FORCEPROP 0 LASTPIN (2375 3150) $PN 45
J 0
(2385 3160);
DISPLAY 0.680851 (2385 3160);
PAINT MONO (2385 3160);
FORCEPROP 0 LASTPIN (2375 3200) $PN 44
J 0
(2385 3210);
DISPLAY 0.680851 (2385 3210);
PAINT MONO (2385 3210);
FORCEPROP 0 LASTPIN (2375 2100) $PN 138
J 0
(2385 2110);
DISPLAY 0.680851 (2385 2110);
PAINT MONO (2385 2110);
FORCEPROP 0 LASTPIN (2375 2150) $PN 137
J 0
(2385 2160);
DISPLAY 0.680851 (2385 2160);
PAINT MONO (2385 2160);
FORCEPROP 0 LASTPIN (2375 3250) $PN 56
J 0
(2385 3260);
DISPLAY 0.680851 (2385 3260);
PAINT MONO (2385 3260);
FORCEPROP 0 LASTPIN (2375 3300) $PN 55
J 0
(2385 3310);
DISPLAY 0.680851 (2385 3310);
PAINT MONO (2385 3310);
FORCEPROP 0 LASTPIN (2375 2200) $PN 238
J 0
(2385 2210);
DISPLAY 0.680851 (2385 2210);
PAINT MONO (2385 2210);
FORCEPROP 0 LASTPIN (2375 2250) $PN 239
J 0
(2385 2260);
DISPLAY 0.680851 (2385 2260);
PAINT MONO (2385 2260);
FORCEPROP 0 LASTPIN (2375 3350) $PN 156
J 0
(2385 3360);
DISPLAY 0.680851 (2385 3360);
PAINT MONO (2385 3360);
FORCEPROP 0 LASTPIN (2375 3400) $PN 157
J 0
(2385 3410);
DISPLAY 0.680851 (2385 3410);
PAINT MONO (2385 3410);
FORCEPROP 0 LASTPIN (2375 2300) $PN 249
J 0
(2385 2310);
DISPLAY 0.680851 (2385 2310);
PAINT MONO (2385 2310);
FORCEPROP 0 LASTPIN (2375 2350) $PN 250
J 0
(2385 2360);
DISPLAY 0.680851 (2385 2360);
PAINT MONO (2385 2360);
FORCEPROP 0 LASTPIN (2375 3450) $PN 167
J 0
(2385 3460);
DISPLAY 0.680851 (2385 3460);
PAINT MONO (2385 3460);
FORCEPROP 0 LASTPIN (2375 3500) $PN 168
J 0
(2385 3510);
DISPLAY 0.680851 (2385 3510);
PAINT MONO (2385 3510);
FORCEPROP 0 LASTPIN (2375 2400) $PN 260
J 0
(2385 2410);
DISPLAY 0.680851 (2385 2410);
PAINT MONO (2385 2410);
FORCEPROP 0 LASTPIN (2375 2450) $PN 261
J 0
(2385 2460);
DISPLAY 0.680851 (2385 2460);
PAINT MONO (2385 2460);
FORCEPROP 0 LASTPIN (2375 3550) $PN 178
J 0
(2385 3560);
DISPLAY 0.680851 (2385 3560);
PAINT MONO (2385 3560);
FORCEPROP 0 LASTPIN (2375 3600) $PN 179
J 0
(2385 3610);
DISPLAY 0.680851 (2385 3610);
PAINT MONO (2385 3610);
FORCEPROP 0 LASTPIN (2375 2500) $PN 271
J 0
(2385 2510);
DISPLAY 0.680851 (2385 2510);
PAINT MONO (2385 2510);
FORCEPROP 0 LASTPIN (2375 2550) $PN 272
J 0
(2385 2560);
DISPLAY 0.680851 (2385 2560);
PAINT MONO (2385 2560);
FORCEPROP 0 LASTPIN (2375 3650) $PN 189
J 0
(2385 3660);
DISPLAY 0.680851 (2385 3660);
PAINT MONO (2385 3660);
FORCEPROP 0 LASTPIN (2375 3700) $PN 190
J 0
(2385 3710);
DISPLAY 0.680851 (2385 3710);
PAINT MONO (2385 3710);
FORCEPROP 0 LASTPIN (2375 2600) $PN 282
J 0
(2385 2610);
DISPLAY 0.680851 (2385 2610);
PAINT MONO (2385 2610);
FORCEPROP 0 LASTPIN (2375 2650) $PN 283
J 0
(2385 2660);
DISPLAY 0.680851 (2385 2660);
PAINT MONO (2385 2660);
FORCEPROP 0 LASTPIN (2375 3750) $PN 200
J 0
(2385 3760);
DISPLAY 0.680851 (2385 3760);
PAINT MONO (2385 3760);
FORCEPROP 0 LASTPIN (2375 3800) $PN 201
J 0
(2385 3810);
DISPLAY 0.680851 (2385 3810);
PAINT MONO (2385 3810);
FORCEPROP 0 LASTPIN (2375 2700) $PN 94
J 0
(2385 2710);
DISPLAY 0.680851 (2385 2710);
PAINT MONO (2385 2710);
FORCEPROP 0 LASTPIN (2375 2750) $PN 93
J 0
(2385 2760);
DISPLAY 0.680851 (2385 2760);
PAINT MONO (2385 2760);
FORCEPROP 2 LAST CDS_LIB pure_quanta
J 0
(1625 2800);
DISPLAY INVISIBLE (1625 2800);
FORCEPROP 1 LAST CDS_LMAN_SYM_OUTLINE -600,1150,600,-1150
J 0
(1625 2800);
DISPLAY 0.468085 (1625 2800);
PAINT GREEN (1625 2800);
DISPLAY INVISIBLE (1625 2800);
FORCEPROP 1 LAST NEEDS_NO_SIZE TRUE
J 0
(1625 2800);
DISPLAY 0.723404 (1625 2800);
PAINT GREEN (1625 2800);
DISPLAY INVISIBLE (1625 2800);
FORCEPROP 1 LAST PATH I178
J 0
(1625 2800);
DISPLAY 0.723404 (1625 2800);
PAINT GREEN (1625 2800);
DISPLAY INVISIBLE (1625 2800);
FORCEPROP 0 LAST $SEC 2
J 0
(1025 4375);
DISPLAY 0.680851 (1025 4375);
PAINT MONO (1025 4375);
DISPLAY INVISIBLE (1025 4375);
FORCEPROP 0 LAST CDS_SEC 2
J 0
(1025 4375);
DISPLAY 1.021277 (1025 4375);
DISPLAY INVISIBLE (1025 4375);
FORCEADD OFFPAGE..1
(-1600 1025);
FORCEPROP 2 LAST $XR7 105 
J 0
(-2692 1025);
DISPLAY 0.638298 (-2692 1025);
PAINT MONO (-2692 1025);
FORCEPROP 2 LAST $XR6 104 
J 0
(-2572 1025);
DISPLAY 0.638298 (-2572 1025);
PAINT MONO (-2572 1025);
FORCEPROP 2 LAST $XR5 103 
J 0
(-2452 1025);
DISPLAY 0.638298 (-2452 1025);
PAINT MONO (-2452 1025);
FORCEPROP 2 LAST $XR4 102 
J 0
(-2332 1025);
DISPLAY 0.638298 (-2332 1025);
PAINT MONO (-2332 1025);
FORCEPROP 2 LAST $XR3 101 
J 0
(-2212 1025);
DISPLAY 0.638298 (-2212 1025);
PAINT MONO (-2212 1025);
FORCEPROP 2 LAST $XR2 100 
J 0
(-2092 1025);
DISPLAY 0.638298 (-2092 1025);
PAINT MONO (-2092 1025);
FORCEPROP 2 LAST $XR1 98 
J 0
(-1972 1025);
DISPLAY 0.638298 (-1972 1025);
PAINT MONO (-1972 1025);
FORCEPROP 2 LAST $XR0 230 
J 0
(-1882 1025);
DISPLAY 0.638298 (-1882 1025);
PAINT MONO (-1882 1025);
FORCEPROP 2 LAST CDS_LIB standard
J 2
(-1600 1025);
DISPLAY INVISIBLE (-1600 1025);
FORCEPROP 1 LAST OFFPAGE TRUE
J 0
(-1275 900);
DISPLAY 0.872340 (-1275 900);
DISPLAY INVISIBLE (-1275 900);
FORCEPROP 1 LAST COMMENT_BODY TRUE
J 0
(-1475 925);
DISPLAY 0.872340 (-1475 925);
PAINT GREEN (-1475 925);
DISPLAY INVISIBLE (-1475 925);
FORCEPROP 2 LAST PATH I179
J 2
(-1775 1100);
DISPLAY 1.021277 (-1775 1100);
DISPLAY INVISIBLE (-1775 1100);
FORCEADD OFFPAGE..1
(-2800 2700);
FORCEPROP 2 LAST $XR0 51 
J 0
(-3021 2700);
DISPLAY 0.638298 (-3021 2700);
PAINT MONO (-3021 2700);
FORCEPROP 2 LAST CDS_LIB standard
J 0
(-2800 2700);
PAINT MONO (-2800 2700);
DISPLAY INVISIBLE (-2800 2700);
FORCEPROP 1 LAST OFFPAGE TRUE
J 0
(-2475 2575);
DISPLAY 0.872340 (-2475 2575);
DISPLAY INVISIBLE (-2475 2575);
FORCEPROP 1 LAST COMMENT_BODY TRUE
J 0
(-2675 2600);
DISPLAY 0.872340 (-2675 2600);
PAINT GREEN (-2675 2600);
DISPLAY INVISIBLE (-2675 2600);
FORCEPROP 2 LAST PATH I18
J 0
(-2750 2775);
DISPLAY 1.021277 (-2750 2775);
DISPLAY INVISIBLE (-2750 2775);
FORCEADD Q_RES..1
(-2850 1075);
FORCEPROP 1 LAST PART_NUMBER CS04992FB07
J 0
(-2750 1050);
DISPLAY 0.404255 (-2750 1050);
DISPLAY INVISIBLE (-2750 1050);
FORCEPROP 1 LAST VALUE 49.9
J 2
(-2625 1075);
DISPLAY 0.510638 (-2625 1075);
FORCEPROP 1 LAST MATERIAL CHIP
J 0
(-3075 1050);
DISPLAY 0.404255 (-3075 1050);
FORCEPROP 1 LAST $LOCATION R3892
J 0
(-3100 1075);
DISPLAY 0.638298 (-3100 1075);
FORCEPROP 1 LASTPIN (-2950 1075) $PN 1
J 0
(-2938 1087);
DISPLAY 0.787234 (-2938 1087);
PAINT MONO (-2938 1087);
FORCEPROP 1 LASTPIN (-2750 1075) $PN 2
J 0
(-2788 1087);
DISPLAY 0.787234 (-2788 1087);
PAINT MONO (-2788 1087);
FORCEPROP 1 LAST WATTAGE 1/16W
J 2
(-2550 1025);
DISPLAY 0.404255 (-2550 1025);
DISPLAY INVISIBLE (-2550 1025);
FORCEPROP 1 LAST TOLERANCE 1%
J 0
(-2625 1075);
DISPLAY 0.510638 (-2625 1075);
DISPLAY INVISIBLE (-2625 1075);
FORCEPROP 1 LAST PACK_TYPE 0402LF
J 0
(-2550 1075);
DISPLAY 0.510638 (-2550 1075);
DISPLAY INVISIBLE (-2550 1075);
FORCEPROP 2 LAST CDS_LIB pure_quanta
J 0
(-2850 1075);
DISPLAY INVISIBLE (-2850 1075);
FORCEPROP 1 LAST PATH I180
J 0
(-2900 1225);
DISPLAY 0.978723 (-2900 1225);
PAINT WHITE (-2900 1225);
DISPLAY INVISIBLE (-2900 1225);
FORCEPROP 0 LAST CDS_LOCATION R3892
J 0
(-3000 1125);
DISPLAY 1.021277 (-3000 1125);
DISPLAY INVISIBLE (-3000 1125);
FORCEPROP 0 LAST $SEC 1
J 0
(-3000 1125);
DISPLAY 0.680851 (-3000 1125);
PAINT MONO (-3000 1125);
DISPLAY INVISIBLE (-3000 1125);
FORCEPROP 0 LAST CDS_SEC 1
J 0
(-3000 1125);
DISPLAY 1.021277 (-3000 1125);
DISPLAY INVISIBLE (-3000 1125);
FORCEADD OFFPAGE..1
(-2800 2850);
FORCEPROP 2 LAST $XR0 51 
J 0
(-3021 2850);
DISPLAY 0.638298 (-3021 2850);
PAINT MONO (-3021 2850);
FORCEPROP 2 LAST CDS_LIB standard
J 0
(-2800 2850);
PAINT MONO (-2800 2850);
DISPLAY INVISIBLE (-2800 2850);
FORCEPROP 1 LAST OFFPAGE TRUE
J 0
(-2475 2725);
DISPLAY 0.872340 (-2475 2725);
DISPLAY INVISIBLE (-2475 2725);
FORCEPROP 1 LAST COMMENT_BODY TRUE
J 0
(-2675 2750);
DISPLAY 0.872340 (-2675 2750);
PAINT GREEN (-2675 2750);
DISPLAY INVISIBLE (-2675 2750);
FORCEPROP 2 LAST PATH I19
J 0
(-2750 2925);
DISPLAY 1.021277 (-2750 2925);
DISPLAY INVISIBLE (-2750 2925);
FORCEADD Q_RES..2
(-1650 -350);
FORCEPROP 1 LAST PART_NUMBER CS31542FB02
J 0
(-1610 -475);
DISPLAY 0.978723 (-1610 -475);
DISPLAY INVISIBLE (-1610 -475);
FORCEPROP 1 LAST PACK_TYPE 0402LF
J 0
(-1610 -525);
DISPLAY 0.978723 (-1610 -525);
FORCEPROP 1 LAST MATERIAL CHIP
J 0
(-1610 -425);
DISPLAY 0.978723 (-1610 -425);
FORCEPROP 1 LAST TOLERANCE 1%
J 0
(-1605 -325);
DISPLAY 0.978723 (-1605 -325);
FORCEPROP 1 LAST VALUE 15.4K
J 0
(-1605 -275);
DISPLAY 0.978723 (-1605 -275);
FORCEPROP 1 LAST WATTAGE 1/16W
J 0
(-1610 -375);
DISPLAY 0.978723 (-1610 -375);
FORCEPROP 1 LAST $LOCATION R43
J 0
(-1605 -225);
DISPLAY 1.234043 (-1605 -225);
FORCEPROP 1 LASTPIN (-1650 -250) $PN 1
J 0
(-1645 -288);
DISPLAY 0.787234 (-1645 -288);
PAINT MONO (-1645 -288);
FORCEPROP 1 LASTPIN (-1650 -450) $PN 2
J 0
(-1645 -440);
DISPLAY 0.787234 (-1645 -440);
PAINT MONO (-1645 -440);
FORCEPROP 2 LAST CDS_LIB pure_quanta
J 0
(-1650 -350);
DISPLAY INVISIBLE (-1650 -350);
FORCEPROP 1 LAST PATH I2
J 0
(-1600 -175);
DISPLAY 0.978723 (-1600 -175);
PAINT WHITE (-1600 -175);
DISPLAY INVISIBLE (-1600 -175);
FORCEPROP 2 LAST CDS_LOCATION R43
J 0
(-1600 -125);
DISPLAY 1.021277 (-1600 -125);
DISPLAY INVISIBLE (-1600 -125);
FORCEPROP 0 LAST $SEC 1
J 0
(-1600 -150);
DISPLAY 0.680851 (-1600 -150);
PAINT MONO (-1600 -150);
DISPLAY INVISIBLE (-1600 -150);
FORCEPROP 2 LAST CDS_SEC 1
J 0
(-1600 -125);
DISPLAY 1.021277 (-1600 -125);
DISPLAY INVISIBLE (-1600 -125);
FORCEADD OFFPAGE..1
(-2800 2800);
FORCEPROP 2 LAST $XR0 51 
J 0
(-3021 2800);
DISPLAY 0.638298 (-3021 2800);
PAINT MONO (-3021 2800);
FORCEPROP 2 LAST CDS_LIB standard
J 0
(-2800 2800);
PAINT MONO (-2800 2800);
DISPLAY INVISIBLE (-2800 2800);
FORCEPROP 1 LAST OFFPAGE TRUE
J 0
(-2475 2675);
DISPLAY 0.872340 (-2475 2675);
DISPLAY INVISIBLE (-2475 2675);
FORCEPROP 1 LAST COMMENT_BODY TRUE
J 0
(-2675 2700);
DISPLAY 0.872340 (-2675 2700);
PAINT GREEN (-2675 2700);
DISPLAY INVISIBLE (-2675 2700);
FORCEPROP 2 LAST PATH I20
J 0
(-2750 2875);
DISPLAY 1.021277 (-2750 2875);
DISPLAY INVISIBLE (-2750 2875);
FORCEADD OFFPAGE..1
(-2800 2950);
FORCEPROP 2 LAST $XR1 98 
J 0
(-3111 2950);
DISPLAY 0.638298 (-3111 2950);
PAINT MONO (-3111 2950);
FORCEPROP 2 LAST $XR0 51 
J 0
(-3021 2950);
DISPLAY 0.638298 (-3021 2950);
PAINT MONO (-3021 2950);
FORCEPROP 2 LAST CDS_LIB standard
J 0
(-2800 2950);
PAINT MONO (-2800 2950);
DISPLAY INVISIBLE (-2800 2950);
FORCEPROP 1 LAST OFFPAGE TRUE
J 0
(-2475 2825);
DISPLAY 0.872340 (-2475 2825);
DISPLAY INVISIBLE (-2475 2825);
FORCEPROP 1 LAST COMMENT_BODY TRUE
J 0
(-2675 2850);
DISPLAY 0.872340 (-2675 2850);
PAINT GREEN (-2675 2850);
DISPLAY INVISIBLE (-2675 2850);
FORCEPROP 2 LAST PATH I21
J 0
(-2750 3025);
DISPLAY 1.021277 (-2750 3025);
DISPLAY INVISIBLE (-2750 3025);
FORCEADD OFFPAGE..1
(-2800 3000);
FORCEPROP 2 LAST $XR1 98 
J 0
(-3111 3000);
DISPLAY 0.638298 (-3111 3000);
PAINT MONO (-3111 3000);
FORCEPROP 2 LAST $XR0 51 
J 0
(-3021 3000);
DISPLAY 0.638298 (-3021 3000);
PAINT MONO (-3021 3000);
FORCEPROP 2 LAST CDS_LIB standard
J 0
(-2800 3000);
PAINT MONO (-2800 3000);
DISPLAY INVISIBLE (-2800 3000);
FORCEPROP 1 LAST OFFPAGE TRUE
J 0
(-2475 2875);
DISPLAY 0.872340 (-2475 2875);
DISPLAY INVISIBLE (-2475 2875);
FORCEPROP 1 LAST COMMENT_BODY TRUE
J 0
(-2675 2900);
DISPLAY 0.872340 (-2675 2900);
PAINT GREEN (-2675 2900);
DISPLAY INVISIBLE (-2675 2900);
FORCEPROP 2 LAST PATH I22
J 0
(-2750 3075);
DISPLAY 1.021277 (-2750 3075);
DISPLAY INVISIBLE (-2750 3075);
FORCEADD OFFPAGE..1
(-2800 3425);
FORCEPROP 2 LAST $XR1 98 
J 0
(-3111 3425);
DISPLAY 0.638298 (-3111 3425);
PAINT MONO (-3111 3425);
FORCEPROP 2 LAST $XR0 51 
J 0
(-3021 3425);
DISPLAY 0.638298 (-3021 3425);
PAINT MONO (-3021 3425);
FORCEPROP 2 LAST CDS_LIB standard
J 0
(-2800 3425);
PAINT MONO (-2800 3425);
DISPLAY INVISIBLE (-2800 3425);
FORCEPROP 1 LAST OFFPAGE TRUE
J 0
(-2475 3300);
DISPLAY 0.872340 (-2475 3300);
DISPLAY INVISIBLE (-2475 3300);
FORCEPROP 1 LAST COMMENT_BODY TRUE
J 0
(-2675 3325);
DISPLAY 0.872340 (-2675 3325);
PAINT GREEN (-2675 3325);
DISPLAY INVISIBLE (-2675 3325);
FORCEPROP 2 LAST PATH I23
J 0
(-2750 3500);
DISPLAY 1.021277 (-2750 3500);
DISPLAY INVISIBLE (-2750 3500);
FORCEADD SCONN288_ADR50017P087CC..1
(-1050 2075);
FORCEPROP 1 LAST PART_NUMBER DFHST8FS460
J 0
(-1495 4085);
DISPLAY 0.723404 (-1495 4085);
PAINT GREEN (-1495 4085);
DISPLAY INVISIBLE (-1495 4085);
FORCEPROP 2 LAST PART_TYPE SMLF
J 0
(-1500 4250);
DISPLAY 1.021277 (-1500 4250);
FORCEPROP 2 LAST VALUE SCONN288_ADR50017-P087CC
J 0
(-1500 4200);
DISPLAY 1.021277 (-1500 4200);
FORCEPROP 1 LAST MATERIAL IO
J 0
(-1495 3958);
DISPLAY 0.723404 (-1495 3958);
PAINT GREEN (-1495 3958);
FORCEPROP 1 LAST $LOCATION J18
J 0
(-1500 4150);
DISPLAY 0.723404 (-1500 4150);
PAINT GREEN (-1500 4150);
FORCEPROP 0 LASTPIN (-1650 1450) $PN 62
J 2
(-1660 1460);
DISPLAY 0.680851 (-1660 1460);
PAINT MONO (-1660 1460);
FORCEPROP 0 LASTPIN (-1650 3500) $PN 66
J 2
(-1660 3510);
DISPLAY 0.680851 (-1660 3510);
PAINT MONO (-1660 3510);
FORCEPROP 0 LASTPIN (-1650 3100) $PN 76
J 2
(-1660 3110);
DISPLAY 0.680851 (-1660 3110);
PAINT MONO (-1660 3110);
FORCEPROP 0 LASTPIN (-1650 3550) $PN 211
J 2
(-1660 3560);
DISPLAY 0.680851 (-1660 3560);
PAINT MONO (-1660 3560);
FORCEPROP 0 LASTPIN (-1650 3150) $PN 221
J 2
(-1660 3160);
DISPLAY 0.680851 (-1660 3160);
PAINT MONO (-1660 3160);
FORCEPROP 0 LASTPIN (-1650 3600) $PN 68
J 2
(-1660 3610);
DISPLAY 0.680851 (-1660 3610);
PAINT MONO (-1660 3610);
FORCEPROP 0 LASTPIN (-1650 3200) $PN 78
J 2
(-1660 3210);
DISPLAY 0.680851 (-1660 3210);
PAINT MONO (-1660 3210);
FORCEPROP 0 LASTPIN (-1650 3650) $PN 213
J 2
(-1660 3660);
DISPLAY 0.680851 (-1660 3660);
PAINT MONO (-1660 3660);
FORCEPROP 0 LASTPIN (-1650 3250) $PN 223
J 2
(-1660 3260);
DISPLAY 0.680851 (-1660 3260);
PAINT MONO (-1660 3260);
FORCEPROP 0 LASTPIN (-1650 3700) $PN 70
J 2
(-1660 3710);
DISPLAY 0.680851 (-1660 3710);
PAINT MONO (-1660 3710);
FORCEPROP 0 LASTPIN (-1650 3300) $PN 80
J 2
(-1660 3310);
DISPLAY 0.680851 (-1660 3310);
PAINT MONO (-1660 3310);
FORCEPROP 0 LASTPIN (-1650 3750) $PN 215
J 2
(-1660 3760);
DISPLAY 0.680851 (-1660 3760);
PAINT MONO (-1660 3760);
FORCEPROP 0 LASTPIN (-1650 3350) $PN 225
J 2
(-1660 3360);
DISPLAY 0.680851 (-1660 3360);
PAINT MONO (-1660 3360);
FORCEPROP 0 LASTPIN (-1650 3800) $PN 72
J 2
(-1660 3810);
DISPLAY 0.680851 (-1660 3810);
PAINT MONO (-1660 3810);
FORCEPROP 0 LASTPIN (-1650 3400) $PN 82
J 2
(-1660 3410);
DISPLAY 0.680851 (-1660 3410);
PAINT MONO (-1660 3410);
FORCEPROP 0 LASTPIN (-1650 2050) $PN 51
J 2
(-1660 2060);
DISPLAY 0.680851 (-1660 2060);
PAINT MONO (-1660 2060);
FORCEPROP 0 LASTPIN (-1650 1600) $PN 96
J 2
(-1660 1610);
DISPLAY 0.680851 (-1660 1610);
PAINT MONO (-1660 1610);
FORCEPROP 0 LASTPIN (-1650 2100) $PN 53
J 2
(-1660 2110);
DISPLAY 0.680851 (-1660 2110);
PAINT MONO (-1660 2110);
FORCEPROP 0 LASTPIN (-1650 1650) $PN 98
J 2
(-1660 1660);
DISPLAY 0.680851 (-1660 1660);
PAINT MONO (-1660 1660);
FORCEPROP 0 LASTPIN (-1650 2150) $PN 196
J 2
(-1660 2160);
DISPLAY 0.680851 (-1660 2160);
PAINT MONO (-1660 2160);
FORCEPROP 0 LASTPIN (-1650 1700) $PN 241
J 2
(-1660 1710);
DISPLAY 0.680851 (-1660 1710);
PAINT MONO (-1660 1710);
FORCEPROP 0 LASTPIN (-1650 2200) $PN 198
J 2
(-1660 2210);
DISPLAY 0.680851 (-1660 2210);
PAINT MONO (-1660 2210);
FORCEPROP 0 LASTPIN (-1650 1750) $PN 243
J 2
(-1660 1760);
DISPLAY 0.680851 (-1660 1760);
PAINT MONO (-1660 1760);
FORCEPROP 0 LASTPIN (-1650 2250) $PN 58
J 2
(-1660 2260);
DISPLAY 0.680851 (-1660 2260);
PAINT MONO (-1660 2260);
FORCEPROP 0 LASTPIN (-1650 1800) $PN 89
J 2
(-1660 1810);
DISPLAY 0.680851 (-1660 1810);
PAINT MONO (-1660 1810);
FORCEPROP 0 LASTPIN (-1650 2300) $PN 60
J 2
(-1660 2310);
DISPLAY 0.680851 (-1660 2310);
PAINT MONO (-1660 2310);
FORCEPROP 0 LASTPIN (-1650 1850) $PN 91
J 2
(-1660 1860);
DISPLAY 0.680851 (-1660 1860);
PAINT MONO (-1660 1860);
FORCEPROP 0 LASTPIN (-1650 2350) $PN 203
J 2
(-1660 2360);
DISPLAY 0.680851 (-1660 2360);
PAINT MONO (-1660 2360);
FORCEPROP 0 LASTPIN (-1650 1900) $PN 234
J 2
(-1660 1910);
DISPLAY 0.680851 (-1660 1910);
PAINT MONO (-1660 1910);
FORCEPROP 0 LASTPIN (-1650 2400) $PN 205
J 2
(-1660 2410);
DISPLAY 0.680851 (-1660 2410);
PAINT MONO (-1660 2410);
FORCEPROP 0 LASTPIN (-1650 1950) $PN 236
J 2
(-1660 1960);
DISPLAY 0.680851 (-1660 1960);
PAINT MONO (-1660 1960);
FORCEPROP 0 LASTPIN (-1650 2500) $PN 218
J 2
(-1660 2510);
DISPLAY 0.680851 (-1660 2510);
PAINT MONO (-1660 2510);
FORCEPROP 0 LASTPIN (-1650 2550) $PN 217
J 2
(-1660 2560);
DISPLAY 0.680851 (-1660 2560);
PAINT MONO (-1660 2560);
FORCEPROP 0 LASTPIN (-1650 2800) $PN 64
J 2
(-1660 2810);
DISPLAY 0.680851 (-1660 2810);
PAINT MONO (-1660 2810);
FORCEPROP 0 LASTPIN (-1650 2650) $PN 84
J 2
(-1660 2660);
DISPLAY 0.680851 (-1660 2660);
PAINT MONO (-1660 2660);
FORCEPROP 0 LASTPIN (-1650 2850) $PN 209
J 2
(-1660 2860);
DISPLAY 0.680851 (-1660 2860);
PAINT MONO (-1660 2860);
FORCEPROP 0 LASTPIN (-1650 2700) $PN 229
J 2
(-1660 2710);
DISPLAY 0.680851 (-1660 2710);
PAINT MONO (-1660 2710);
FORCEPROP 0 LASTPIN (-450 2250) $PN 7
J 0
(-440 2260);
DISPLAY 0.680851 (-440 2260);
PAINT MONO (-440 2260);
FORCEPROP 0 LASTPIN (-450 600) $PN 100
J 0
(-440 610);
DISPLAY 0.680851 (-440 610);
PAINT MONO (-440 610);
FORCEPROP 0 LASTPIN (-450 2300) $PN 9
J 0
(-440 2310);
DISPLAY 0.680851 (-440 2310);
PAINT MONO (-440 2310);
FORCEPROP 0 LASTPIN (-450 650) $PN 102
J 0
(-440 660);
DISPLAY 0.680851 (-440 660);
PAINT MONO (-440 660);
FORCEPROP 0 LASTPIN (-450 2350) $PN 152
J 0
(-440 2360);
DISPLAY 0.680851 (-440 2360);
PAINT MONO (-440 2360);
FORCEPROP 0 LASTPIN (-450 700) $PN 245
J 0
(-440 710);
DISPLAY 0.680851 (-440 710);
PAINT MONO (-440 710);
FORCEPROP 0 LASTPIN (-450 2400) $PN 154
J 0
(-440 2410);
DISPLAY 0.680851 (-440 2410);
PAINT MONO (-440 2410);
FORCEPROP 0 LASTPIN (-450 750) $PN 247
J 0
(-440 760);
DISPLAY 0.680851 (-440 760);
PAINT MONO (-440 760);
FORCEPROP 0 LASTPIN (-450 2450) $PN 14
J 0
(-440 2460);
DISPLAY 0.680851 (-440 2460);
PAINT MONO (-440 2460);
FORCEPROP 0 LASTPIN (-450 800) $PN 107
J 0
(-440 810);
DISPLAY 0.680851 (-440 810);
PAINT MONO (-440 810);
FORCEPROP 0 LASTPIN (-450 2500) $PN 16
J 0
(-440 2510);
DISPLAY 0.680851 (-440 2510);
PAINT MONO (-440 2510);
FORCEPROP 0 LASTPIN (-450 850) $PN 109
J 0
(-440 860);
DISPLAY 0.680851 (-440 860);
PAINT MONO (-440 860);
FORCEPROP 0 LASTPIN (-450 2550) $PN 159
J 0
(-440 2560);
DISPLAY 0.680851 (-440 2560);
PAINT MONO (-440 2560);
FORCEPROP 0 LASTPIN (-450 900) $PN 252
J 0
(-440 910);
DISPLAY 0.680851 (-440 910);
PAINT MONO (-440 910);
FORCEPROP 0 LASTPIN (-450 2600) $PN 161
J 0
(-440 2610);
DISPLAY 0.680851 (-440 2610);
PAINT MONO (-440 2610);
FORCEPROP 0 LASTPIN (-450 950) $PN 254
J 0
(-440 960);
DISPLAY 0.680851 (-440 960);
PAINT MONO (-440 960);
FORCEPROP 0 LASTPIN (-450 2650) $PN 18
J 0
(-440 2660);
DISPLAY 0.680851 (-440 2660);
PAINT MONO (-440 2660);
FORCEPROP 0 LASTPIN (-450 1000) $PN 111
J 0
(-440 1010);
DISPLAY 0.680851 (-440 1010);
PAINT MONO (-440 1010);
FORCEPROP 0 LASTPIN (-450 2700) $PN 20
J 0
(-440 2710);
DISPLAY 0.680851 (-440 2710);
PAINT MONO (-440 2710);
FORCEPROP 0 LASTPIN (-450 1050) $PN 113
J 0
(-440 1060);
DISPLAY 0.680851 (-440 1060);
PAINT MONO (-440 1060);
FORCEPROP 0 LASTPIN (-450 2750) $PN 163
J 0
(-440 2760);
DISPLAY 0.680851 (-440 2760);
PAINT MONO (-440 2760);
FORCEPROP 0 LASTPIN (-450 1100) $PN 256
J 0
(-440 1110);
DISPLAY 0.680851 (-440 1110);
PAINT MONO (-440 1110);
FORCEPROP 0 LASTPIN (-450 2800) $PN 165
J 0
(-440 2810);
DISPLAY 0.680851 (-440 2810);
PAINT MONO (-440 2810);
FORCEPROP 0 LASTPIN (-450 1150) $PN 258
J 0
(-440 1160);
DISPLAY 0.680851 (-440 1160);
PAINT MONO (-440 1160);
FORCEPROP 0 LASTPIN (-450 2850) $PN 25
J 0
(-440 2860);
DISPLAY 0.680851 (-440 2860);
PAINT MONO (-440 2860);
FORCEPROP 0 LASTPIN (-450 1200) $PN 118
J 0
(-440 1210);
DISPLAY 0.680851 (-440 1210);
PAINT MONO (-440 1210);
FORCEPROP 0 LASTPIN (-450 2900) $PN 27
J 0
(-440 2910);
DISPLAY 0.680851 (-440 2910);
PAINT MONO (-440 2910);
FORCEPROP 0 LASTPIN (-450 1250) $PN 120
J 0
(-440 1260);
DISPLAY 0.680851 (-440 1260);
PAINT MONO (-440 1260);
FORCEPROP 0 LASTPIN (-450 2950) $PN 170
J 0
(-440 2960);
DISPLAY 0.680851 (-440 2960);
PAINT MONO (-440 2960);
FORCEPROP 0 LASTPIN (-450 1300) $PN 263
J 0
(-440 1310);
DISPLAY 0.680851 (-440 1310);
PAINT MONO (-440 1310);
FORCEPROP 0 LASTPIN (-450 3000) $PN 172
J 0
(-440 3010);
DISPLAY 0.680851 (-440 3010);
PAINT MONO (-440 3010);
FORCEPROP 0 LASTPIN (-450 1350) $PN 265
J 0
(-440 1360);
DISPLAY 0.680851 (-440 1360);
PAINT MONO (-440 1360);
FORCEPROP 0 LASTPIN (-450 3050) $PN 29
J 0
(-440 3060);
DISPLAY 0.680851 (-440 3060);
PAINT MONO (-440 3060);
FORCEPROP 0 LASTPIN (-450 1400) $PN 122
J 0
(-440 1410);
DISPLAY 0.680851 (-440 1410);
PAINT MONO (-440 1410);
FORCEPROP 0 LASTPIN (-450 3100) $PN 31
J 0
(-440 3110);
DISPLAY 0.680851 (-440 3110);
PAINT MONO (-440 3110);
FORCEPROP 0 LASTPIN (-450 1450) $PN 124
J 0
(-440 1460);
DISPLAY 0.680851 (-440 1460);
PAINT MONO (-440 1460);
FORCEPROP 0 LASTPIN (-450 3150) $PN 174
J 0
(-440 3160);
DISPLAY 0.680851 (-440 3160);
PAINT MONO (-440 3160);
FORCEPROP 0 LASTPIN (-450 1500) $PN 267
J 0
(-440 1510);
DISPLAY 0.680851 (-440 1510);
PAINT MONO (-440 1510);
FORCEPROP 0 LASTPIN (-450 3200) $PN 176
J 0
(-440 3210);
DISPLAY 0.680851 (-440 3210);
PAINT MONO (-440 3210);
FORCEPROP 0 LASTPIN (-450 1550) $PN 269
J 0
(-440 1560);
DISPLAY 0.680851 (-440 1560);
PAINT MONO (-440 1560);
FORCEPROP 0 LASTPIN (-450 3250) $PN 36
J 0
(-440 3260);
DISPLAY 0.680851 (-440 3260);
PAINT MONO (-440 3260);
FORCEPROP 0 LASTPIN (-450 1600) $PN 129
J 0
(-440 1610);
DISPLAY 0.680851 (-440 1610);
PAINT MONO (-440 1610);
FORCEPROP 0 LASTPIN (-450 3300) $PN 38
J 0
(-440 3310);
DISPLAY 0.680851 (-440 3310);
PAINT MONO (-440 3310);
FORCEPROP 0 LASTPIN (-450 1650) $PN 131
J 0
(-440 1660);
DISPLAY 0.680851 (-440 1660);
PAINT MONO (-440 1660);
FORCEPROP 0 LASTPIN (-450 3350) $PN 181
J 0
(-440 3360);
DISPLAY 0.680851 (-440 3360);
PAINT MONO (-440 3360);
FORCEPROP 0 LASTPIN (-450 1700) $PN 274
J 0
(-440 1710);
DISPLAY 0.680851 (-440 1710);
PAINT MONO (-440 1710);
FORCEPROP 0 LASTPIN (-450 3400) $PN 183
J 0
(-440 3410);
DISPLAY 0.680851 (-440 3410);
PAINT MONO (-440 3410);
FORCEPROP 0 LASTPIN (-450 1750) $PN 276
J 0
(-440 1760);
DISPLAY 0.680851 (-440 1760);
PAINT MONO (-440 1760);
FORCEPROP 0 LASTPIN (-450 3450) $PN 40
J 0
(-440 3460);
DISPLAY 0.680851 (-440 3460);
PAINT MONO (-440 3460);
FORCEPROP 0 LASTPIN (-450 1800) $PN 133
J 0
(-440 1810);
DISPLAY 0.680851 (-440 1810);
PAINT MONO (-440 1810);
FORCEPROP 0 LASTPIN (-450 3500) $PN 42
J 0
(-440 3510);
DISPLAY 0.680851 (-440 3510);
PAINT MONO (-440 3510);
FORCEPROP 0 LASTPIN (-450 1850) $PN 135
J 0
(-440 1860);
DISPLAY 0.680851 (-440 1860);
PAINT MONO (-440 1860);
FORCEPROP 0 LASTPIN (-450 3550) $PN 185
J 0
(-440 3560);
DISPLAY 0.680851 (-440 3560);
PAINT MONO (-440 3560);
FORCEPROP 0 LASTPIN (-450 1900) $PN 278
J 0
(-440 1910);
DISPLAY 0.680851 (-440 1910);
PAINT MONO (-440 1910);
FORCEPROP 0 LASTPIN (-450 3600) $PN 187
J 0
(-440 3610);
DISPLAY 0.680851 (-440 3610);
PAINT MONO (-440 3610);
FORCEPROP 0 LASTPIN (-450 1950) $PN 280
J 0
(-440 1960);
DISPLAY 0.680851 (-440 1960);
PAINT MONO (-440 1960);
FORCEPROP 0 LASTPIN (-450 3650) $PN 47
J 0
(-440 3660);
DISPLAY 0.680851 (-440 3660);
PAINT MONO (-440 3660);
FORCEPROP 0 LASTPIN (-450 2000) $PN 140
J 0
(-440 2010);
DISPLAY 0.680851 (-440 2010);
PAINT MONO (-440 2010);
FORCEPROP 0 LASTPIN (-450 3700) $PN 49
J 0
(-440 3710);
DISPLAY 0.680851 (-440 3710);
PAINT MONO (-440 3710);
FORCEPROP 0 LASTPIN (-450 2050) $PN 142
J 0
(-440 2060);
DISPLAY 0.680851 (-440 2060);
PAINT MONO (-440 2060);
FORCEPROP 0 LASTPIN (-450 3750) $PN 192
J 0
(-440 3760);
DISPLAY 0.680851 (-440 3760);
PAINT MONO (-440 3760);
FORCEPROP 0 LASTPIN (-450 2100) $PN 285
J 0
(-440 2110);
DISPLAY 0.680851 (-440 2110);
PAINT MONO (-440 2110);
FORCEPROP 0 LASTPIN (-450 3800) $PN 194
J 0
(-440 3810);
DISPLAY 0.680851 (-440 3810);
PAINT MONO (-440 3810);
FORCEPROP 0 LASTPIN (-450 2150) $PN 287
J 0
(-440 2160);
DISPLAY 0.680851 (-440 2160);
PAINT MONO (-440 2160);
FORCEPROP 0 LASTPIN (-1650 1300) $PN 148
J 2
(-1660 1310);
DISPLAY 0.680851 (-1660 1310);
PAINT MONO (-1660 1310);
FORCEPROP 0 LASTPIN (-1650 1200) $PN 4
J 2
(-1660 1210);
DISPLAY 0.680851 (-1660 1210);
PAINT MONO (-1660 1210);
FORCEPROP 0 LASTPIN (-1650 1250) $PN 5
J 2
(-1660 1260);
DISPLAY 0.680851 (-1660 1260);
PAINT MONO (-1660 1260);
FORCEPROP 0 LASTPIN (-1650 400) $PN 86
J 2
(-1660 410);
DISPLAY 0.680851 (-1660 410);
PAINT MONO (-1660 410);
FORCEPROP 0 LASTPIN (-1650 350) $PN 87
J 2
(-1660 360);
DISPLAY 0.680851 (-1660 360);
PAINT MONO (-1660 360);
FORCEPROP 0 LASTPIN (-1650 3000) $PN 74
J 2
(-1660 3010);
DISPLAY 0.680851 (-1660 3010);
PAINT MONO (-1660 3010);
FORCEPROP 0 LASTPIN (-1650 2950) $PN 227
J 2
(-1660 2960);
DISPLAY 0.680851 (-1660 2960);
PAINT MONO (-1660 2960);
FORCEPROP 0 LASTPIN (-1650 950) $PN 147
J 2
(-1660 960);
DISPLAY 0.680851 (-1660 960);
PAINT MONO (-1660 960);
FORCEPROP 0 LASTPIN (-1650 1500) $PN 207
J 2
(-1660 1510);
DISPLAY 0.680851 (-1660 1510);
PAINT MONO (-1660 1510);
FORCEPROP 0 LASTPIN (-1650 550) $PN 2
J 2
(-1660 560);
DISPLAY 0.680851 (-1660 560);
PAINT MONO (-1660 560);
FORCEPROP 0 LASTPIN (-1650 600) $PN 144
J 2
(-1660 610);
DISPLAY 0.680851 (-1660 610);
PAINT MONO (-1660 610);
FORCEPROP 0 LASTPIN (-1650 650) $PN 149
J 2
(-1660 660);
DISPLAY 0.680851 (-1660 660);
PAINT MONO (-1660 660);
FORCEPROP 0 LASTPIN (-1650 700) $PN 150
J 2
(-1660 710);
DISPLAY 0.680851 (-1660 710);
PAINT MONO (-1660 710);
FORCEPROP 0 LASTPIN (-1650 750) $PN 220
J 2
(-1660 760);
DISPLAY 0.680851 (-1660 760);
PAINT MONO (-1660 760);
FORCEPROP 0 LASTPIN (-1650 800) $PN 231
J 2
(-1660 810);
DISPLAY 0.680851 (-1660 810);
PAINT MONO (-1660 810);
FORCEPROP 0 LASTPIN (-1650 850) $PN 232
J 2
(-1660 860);
DISPLAY 0.680851 (-1660 860);
PAINT MONO (-1660 860);
FORCEPROP 0 LASTPIN (-1650 1350) $PN 3
J 2
(-1660 1360);
DISPLAY 0.680851 (-1660 1360);
PAINT MONO (-1660 1360);
FORCEPROP 2 LAST CDS_LIB pure_quanta
J 0
(-1050 2075);
DISPLAY INVISIBLE (-1050 2075);
FORCEPROP 1 LAST CDS_LMAN_SYM_OUTLINE -450,1875,450,-1875
J 0
(-1050 2075);
DISPLAY 0.468085 (-1050 2075);
PAINT GREEN (-1050 2075);
DISPLAY INVISIBLE (-1050 2075);
FORCEPROP 1 LAST NEEDS_NO_SIZE TRUE
J 0
(-1050 2075);
DISPLAY 0.723404 (-1050 2075);
PAINT GREEN (-1050 2075);
DISPLAY INVISIBLE (-1050 2075);
FORCEPROP 1 LAST PATH I24
J 0
(-1050 2075);
DISPLAY 0.723404 (-1050 2075);
PAINT GREEN (-1050 2075);
DISPLAY INVISIBLE (-1050 2075);
FORCEPROP 2 LAST CDS_LOCATION J18
J 0
(-1500 4300);
DISPLAY 1.021277 (-1500 4300);
DISPLAY INVISIBLE (-1500 4300);
FORCEPROP 0 LAST $SEC 1
J 0
(-1500 4300);
DISPLAY 0.680851 (-1500 4300);
PAINT MONO (-1500 4300);
DISPLAY INVISIBLE (-1500 4300);
FORCEPROP 2 LAST CDS_SEC 1
J 0
(-1500 4300);
DISPLAY 1.021277 (-1500 4300);
DISPLAY INVISIBLE (-1500 4300);
FORCEADD TAP..1
R 2
(-1875 1600);
FORCEPROP 3 LASTPIN (-1825 1600) SIG_NAME M_A_CPU1_SB_CB<0>
J 0
(-1815 1610);
DISPLAY 0.659574 (-1815 1610);
PAINT MONO (-1815 1610);
DISPLAY INVISIBLE (-1815 1610);
FORCEPROP 1 LASTPIN (-1825 1600) BN 0
J 2
(-1813 1608);
DISPLAY 0.680851 (-1813 1608);
PAINT GREEN (-1813 1608);
FORCEPROP 2 LAST CDS_LIB standard
J 0
(-1875 1600);
PAINT MONO (-1875 1600);
DISPLAY INVISIBLE (-1875 1600);
FORCEPROP 1 LAST BODY_TYPE PLUMBING
J 2
(-1875 1650);
DISPLAY 0.872340 (-1875 1650);
PAINT GREEN (-1875 1650);
DISPLAY INVISIBLE (-1875 1650);
FORCEPROP 1 LAST HDL_TAP TRUE
J 2
(-2200 1475);
DISPLAY 0.872340 (-2200 1475);
DISPLAY INVISIBLE (-2200 1475);
FORCEPROP 1 LAST PATH I25
J 2
(-1873 1600);
DISPLAY 0.872340 (-1873 1600);
PAINT GREEN (-1873 1600);
DISPLAY INVISIBLE (-1873 1600);
FORCEADD TAP..1
(-225 600);
FORCEPROP 3 LASTPIN (-275 600) SIG_NAME M_A_CPU1_SB_DQ<0>
J 0
(-265 610);
DISPLAY 0.659574 (-265 610);
PAINT MONO (-265 610);
DISPLAY INVISIBLE (-265 610);
FORCEPROP 1 LASTPIN (-275 600) BN 0
J 0
(-287 608);
DISPLAY 0.680851 (-287 608);
PAINT GREEN (-287 608);
FORCEPROP 2 LAST CDS_LIB standard
J 0
(-225 600);
PAINT MONO (-225 600);
DISPLAY INVISIBLE (-225 600);
FORCEPROP 1 LAST BODY_TYPE PLUMBING
J 0
(-225 650);
DISPLAY 0.872340 (-225 650);
PAINT GREEN (-225 650);
DISPLAY INVISIBLE (-225 650);
FORCEPROP 1 LAST HDL_TAP TRUE
J 0
(100 475);
DISPLAY 0.872340 (100 475);
DISPLAY INVISIBLE (100 475);
FORCEPROP 1 LAST PATH I26
J 0
(-227 600);
DISPLAY 0.872340 (-227 600);
PAINT GREEN (-227 600);
DISPLAY INVISIBLE (-227 600);
FORCEADD TAP..1
(-225 650);
FORCEPROP 3 LASTPIN (-275 650) SIG_NAME M_A_CPU1_SB_DQ<1>
J 0
(-265 660);
DISPLAY 0.659574 (-265 660);
PAINT MONO (-265 660);
DISPLAY INVISIBLE (-265 660);
FORCEPROP 1 LASTPIN (-275 650) BN 1
J 0
(-287 658);
DISPLAY 0.680851 (-287 658);
PAINT GREEN (-287 658);
FORCEPROP 2 LAST CDS_LIB standard
J 0
(-225 650);
PAINT MONO (-225 650);
DISPLAY INVISIBLE (-225 650);
FORCEPROP 1 LAST BODY_TYPE PLUMBING
J 0
(-225 700);
DISPLAY 0.872340 (-225 700);
PAINT GREEN (-225 700);
DISPLAY INVISIBLE (-225 700);
FORCEPROP 1 LAST HDL_TAP TRUE
J 0
(100 525);
DISPLAY 0.872340 (100 525);
DISPLAY INVISIBLE (100 525);
FORCEPROP 1 LAST PATH I27
J 0
(-227 650);
DISPLAY 0.872340 (-227 650);
PAINT GREEN (-227 650);
DISPLAY INVISIBLE (-227 650);
FORCEADD TAP..1
(-225 750);
FORCEPROP 3 LASTPIN (-275 750) SIG_NAME M_A_CPU1_SB_DQ<3>
J 0
(-265 760);
DISPLAY 0.659574 (-265 760);
PAINT MONO (-265 760);
DISPLAY INVISIBLE (-265 760);
FORCEPROP 1 LASTPIN (-275 750) BN 3
J 0
(-287 758);
DISPLAY 0.680851 (-287 758);
PAINT GREEN (-287 758);
FORCEPROP 2 LAST CDS_LIB standard
J 0
(-225 750);
PAINT MONO (-225 750);
DISPLAY INVISIBLE (-225 750);
FORCEPROP 1 LAST BODY_TYPE PLUMBING
J 0
(-225 800);
DISPLAY 0.872340 (-225 800);
PAINT GREEN (-225 800);
DISPLAY INVISIBLE (-225 800);
FORCEPROP 1 LAST HDL_TAP TRUE
J 0
(100 625);
DISPLAY 0.872340 (100 625);
DISPLAY INVISIBLE (100 625);
FORCEPROP 1 LAST PATH I28
J 0
(-227 750);
DISPLAY 0.872340 (-227 750);
PAINT GREEN (-227 750);
DISPLAY INVISIBLE (-227 750);
FORCEADD TAP..1
(-225 700);
FORCEPROP 3 LASTPIN (-275 700) SIG_NAME M_A_CPU1_SB_DQ<2>
J 0
(-265 710);
DISPLAY 0.659574 (-265 710);
PAINT MONO (-265 710);
DISPLAY INVISIBLE (-265 710);
FORCEPROP 1 LASTPIN (-275 700) BN 2
J 0
(-287 708);
DISPLAY 0.680851 (-287 708);
PAINT GREEN (-287 708);
FORCEPROP 2 LAST CDS_LIB standard
J 0
(-225 700);
PAINT MONO (-225 700);
DISPLAY INVISIBLE (-225 700);
FORCEPROP 1 LAST BODY_TYPE PLUMBING
J 0
(-225 750);
DISPLAY 0.872340 (-225 750);
PAINT GREEN (-225 750);
DISPLAY INVISIBLE (-225 750);
FORCEPROP 1 LAST HDL_TAP TRUE
J 0
(100 575);
DISPLAY 0.872340 (100 575);
DISPLAY INVISIBLE (100 575);
FORCEPROP 1 LAST PATH I29
J 0
(-227 700);
DISPLAY 0.872340 (-227 700);
PAINT GREEN (-227 700);
DISPLAY INVISIBLE (-227 700);
FORCEADD OFFPAGE..2
R 2
(-2800 -150);
FORCEPROP 2 LAST $XR0 99 
J 0
(-3024 -150);
DISPLAY 0.638298 (-3024 -150);
PAINT MONO (-3024 -150);
FORCEPROP 2 LAST CDS_LIB standard
J 0
(-2800 -150);
PAINT MONO (-2800 -150);
DISPLAY INVISIBLE (-2800 -150);
FORCEPROP 1 LAST OFFPAGE TRUE
J 2
(-3125 -275);
DISPLAY 0.872340 (-3125 -275);
DISPLAY INVISIBLE (-3125 -275);
FORCEPROP 1 LAST COMMENT_BODY TRUE
J 2
(-2755 -245);
DISPLAY 0.872340 (-2755 -245);
PAINT GREEN (-2755 -245);
DISPLAY INVISIBLE (-2755 -245);
FORCEPROP 2 LAST PATH I3
J 0
(-2750 -75);
DISPLAY 1.021277 (-2750 -75);
DISPLAY INVISIBLE (-2750 -75);
FORCEADD TAP..1
(-225 800);
FORCEPROP 3 LASTPIN (-275 800) SIG_NAME M_A_CPU1_SB_DQ<4>
J 0
(-265 810);
DISPLAY 0.659574 (-265 810);
PAINT MONO (-265 810);
DISPLAY INVISIBLE (-265 810);
FORCEPROP 1 LASTPIN (-275 800) BN 4
J 0
(-287 808);
DISPLAY 0.680851 (-287 808);
PAINT GREEN (-287 808);
FORCEPROP 2 LAST CDS_LIB standard
J 0
(-225 800);
PAINT MONO (-225 800);
DISPLAY INVISIBLE (-225 800);
FORCEPROP 1 LAST BODY_TYPE PLUMBING
J 0
(-225 850);
DISPLAY 0.872340 (-225 850);
PAINT GREEN (-225 850);
DISPLAY INVISIBLE (-225 850);
FORCEPROP 1 LAST HDL_TAP TRUE
J 0
(100 675);
DISPLAY 0.872340 (100 675);
DISPLAY INVISIBLE (100 675);
FORCEPROP 1 LAST PATH I30
J 0
(-227 800);
DISPLAY 0.872340 (-227 800);
PAINT GREEN (-227 800);
DISPLAY INVISIBLE (-227 800);
FORCEADD TAP..1
(-225 850);
FORCEPROP 3 LASTPIN (-275 850) SIG_NAME M_A_CPU1_SB_DQ<5>
J 0
(-265 860);
DISPLAY 0.659574 (-265 860);
PAINT MONO (-265 860);
DISPLAY INVISIBLE (-265 860);
FORCEPROP 1 LASTPIN (-275 850) BN 5
J 0
(-287 858);
DISPLAY 0.680851 (-287 858);
PAINT GREEN (-287 858);
FORCEPROP 2 LAST CDS_LIB standard
J 0
(-225 850);
PAINT MONO (-225 850);
DISPLAY INVISIBLE (-225 850);
FORCEPROP 1 LAST BODY_TYPE PLUMBING
J 0
(-225 900);
DISPLAY 0.872340 (-225 900);
PAINT GREEN (-225 900);
DISPLAY INVISIBLE (-225 900);
FORCEPROP 1 LAST HDL_TAP TRUE
J 0
(100 725);
DISPLAY 0.872340 (100 725);
DISPLAY INVISIBLE (100 725);
FORCEPROP 1 LAST PATH I31
J 0
(-227 850);
DISPLAY 0.872340 (-227 850);
PAINT GREEN (-227 850);
DISPLAY INVISIBLE (-227 850);
FORCEADD TAP..1
(-225 900);
FORCEPROP 3 LASTPIN (-275 900) SIG_NAME M_A_CPU1_SB_DQ<6>
J 0
(-265 910);
DISPLAY 0.659574 (-265 910);
PAINT MONO (-265 910);
DISPLAY INVISIBLE (-265 910);
FORCEPROP 1 LASTPIN (-275 900) BN 6
J 0
(-287 908);
DISPLAY 0.680851 (-287 908);
PAINT GREEN (-287 908);
FORCEPROP 2 LAST CDS_LIB standard
J 0
(-225 900);
PAINT MONO (-225 900);
DISPLAY INVISIBLE (-225 900);
FORCEPROP 1 LAST BODY_TYPE PLUMBING
J 0
(-225 950);
DISPLAY 0.872340 (-225 950);
PAINT GREEN (-225 950);
DISPLAY INVISIBLE (-225 950);
FORCEPROP 1 LAST HDL_TAP TRUE
J 0
(100 775);
DISPLAY 0.872340 (100 775);
DISPLAY INVISIBLE (100 775);
FORCEPROP 1 LAST PATH I32
J 0
(-227 900);
DISPLAY 0.872340 (-227 900);
PAINT GREEN (-227 900);
DISPLAY INVISIBLE (-227 900);
FORCEADD TAP..1
(-225 950);
FORCEPROP 3 LASTPIN (-275 950) SIG_NAME M_A_CPU1_SB_DQ<7>
J 0
(-265 960);
DISPLAY 0.659574 (-265 960);
PAINT MONO (-265 960);
DISPLAY INVISIBLE (-265 960);
FORCEPROP 1 LASTPIN (-275 950) BN 7
J 0
(-287 958);
DISPLAY 0.680851 (-287 958);
PAINT GREEN (-287 958);
FORCEPROP 2 LAST CDS_LIB standard
J 0
(-225 950);
PAINT MONO (-225 950);
DISPLAY INVISIBLE (-225 950);
FORCEPROP 1 LAST BODY_TYPE PLUMBING
J 0
(-225 1000);
DISPLAY 0.872340 (-225 1000);
PAINT GREEN (-225 1000);
DISPLAY INVISIBLE (-225 1000);
FORCEPROP 1 LAST HDL_TAP TRUE
J 0
(100 825);
DISPLAY 0.872340 (100 825);
DISPLAY INVISIBLE (100 825);
FORCEPROP 1 LAST PATH I33
J 0
(-227 950);
DISPLAY 0.872340 (-227 950);
PAINT GREEN (-227 950);
DISPLAY INVISIBLE (-227 950);
FORCEADD TAP..1
(-225 1000);
FORCEPROP 3 LASTPIN (-275 1000) SIG_NAME M_A_CPU1_SB_DQ<8>
J 0
(-265 1010);
DISPLAY 0.659574 (-265 1010);
PAINT MONO (-265 1010);
DISPLAY INVISIBLE (-265 1010);
FORCEPROP 1 LASTPIN (-275 1000) BN 8
J 0
(-287 1008);
DISPLAY 0.680851 (-287 1008);
PAINT GREEN (-287 1008);
FORCEPROP 2 LAST CDS_LIB standard
J 0
(-225 1000);
PAINT MONO (-225 1000);
DISPLAY INVISIBLE (-225 1000);
FORCEPROP 1 LAST BODY_TYPE PLUMBING
J 0
(-225 1050);
DISPLAY 0.872340 (-225 1050);
PAINT GREEN (-225 1050);
DISPLAY INVISIBLE (-225 1050);
FORCEPROP 1 LAST HDL_TAP TRUE
J 0
(100 875);
DISPLAY 0.872340 (100 875);
DISPLAY INVISIBLE (100 875);
FORCEPROP 1 LAST PATH I34
J 0
(-227 1000);
DISPLAY 0.872340 (-227 1000);
PAINT GREEN (-227 1000);
DISPLAY INVISIBLE (-227 1000);
FORCEADD TAP..1
(-225 1050);
FORCEPROP 3 LASTPIN (-275 1050) SIG_NAME M_A_CPU1_SB_DQ<9>
J 0
(-265 1060);
DISPLAY 0.659574 (-265 1060);
PAINT MONO (-265 1060);
DISPLAY INVISIBLE (-265 1060);
FORCEPROP 1 LASTPIN (-275 1050) BN 9
J 0
(-287 1058);
DISPLAY 0.680851 (-287 1058);
PAINT GREEN (-287 1058);
FORCEPROP 2 LAST CDS_LIB standard
J 0
(-225 1050);
PAINT MONO (-225 1050);
DISPLAY INVISIBLE (-225 1050);
FORCEPROP 1 LAST BODY_TYPE PLUMBING
J 0
(-225 1100);
DISPLAY 0.872340 (-225 1100);
PAINT GREEN (-225 1100);
DISPLAY INVISIBLE (-225 1100);
FORCEPROP 1 LAST HDL_TAP TRUE
J 0
(100 925);
DISPLAY 0.872340 (100 925);
DISPLAY INVISIBLE (100 925);
FORCEPROP 1 LAST PATH I35
J 0
(-227 1050);
DISPLAY 0.872340 (-227 1050);
PAINT GREEN (-227 1050);
DISPLAY INVISIBLE (-227 1050);
FORCEADD TAP..1
(-225 1100);
FORCEPROP 3 LASTPIN (-275 1100) SIG_NAME M_A_CPU1_SB_DQ<10>
J 0
(-265 1110);
DISPLAY 0.659574 (-265 1110);
PAINT MONO (-265 1110);
DISPLAY INVISIBLE (-265 1110);
FORCEPROP 1 LASTPIN (-275 1100) BN 10
J 0
(-287 1108);
DISPLAY 0.680851 (-287 1108);
PAINT GREEN (-287 1108);
FORCEPROP 2 LAST CDS_LIB standard
J 0
(-225 1100);
PAINT MONO (-225 1100);
DISPLAY INVISIBLE (-225 1100);
FORCEPROP 1 LAST BODY_TYPE PLUMBING
J 0
(-225 1150);
DISPLAY 0.872340 (-225 1150);
PAINT GREEN (-225 1150);
DISPLAY INVISIBLE (-225 1150);
FORCEPROP 1 LAST HDL_TAP TRUE
J 0
(100 975);
DISPLAY 0.872340 (100 975);
DISPLAY INVISIBLE (100 975);
FORCEPROP 1 LAST PATH I36
J 0
(-227 1100);
DISPLAY 0.872340 (-227 1100);
PAINT GREEN (-227 1100);
DISPLAY INVISIBLE (-227 1100);
FORCEADD TAP..1
(-225 1150);
FORCEPROP 3 LASTPIN (-275 1150) SIG_NAME M_A_CPU1_SB_DQ<11>
J 0
(-265 1160);
DISPLAY 0.659574 (-265 1160);
PAINT MONO (-265 1160);
DISPLAY INVISIBLE (-265 1160);
FORCEPROP 1 LASTPIN (-275 1150) BN 11
J 0
(-287 1158);
DISPLAY 0.680851 (-287 1158);
PAINT GREEN (-287 1158);
FORCEPROP 2 LAST CDS_LIB standard
J 0
(-225 1150);
PAINT MONO (-225 1150);
DISPLAY INVISIBLE (-225 1150);
FORCEPROP 1 LAST BODY_TYPE PLUMBING
J 0
(-225 1200);
DISPLAY 0.872340 (-225 1200);
PAINT GREEN (-225 1200);
DISPLAY INVISIBLE (-225 1200);
FORCEPROP 1 LAST HDL_TAP TRUE
J 0
(100 1025);
DISPLAY 0.872340 (100 1025);
DISPLAY INVISIBLE (100 1025);
FORCEPROP 1 LAST PATH I37
J 0
(-227 1150);
DISPLAY 0.872340 (-227 1150);
PAINT GREEN (-227 1150);
DISPLAY INVISIBLE (-227 1150);
FORCEADD TAP..1
(-225 1200);
FORCEPROP 3 LASTPIN (-275 1200) SIG_NAME M_A_CPU1_SB_DQ<12>
J 0
(-265 1210);
DISPLAY 0.659574 (-265 1210);
PAINT MONO (-265 1210);
DISPLAY INVISIBLE (-265 1210);
FORCEPROP 1 LASTPIN (-275 1200) BN 12
J 0
(-287 1208);
DISPLAY 0.680851 (-287 1208);
PAINT GREEN (-287 1208);
FORCEPROP 2 LAST CDS_LIB standard
J 0
(-225 1200);
PAINT MONO (-225 1200);
DISPLAY INVISIBLE (-225 1200);
FORCEPROP 1 LAST BODY_TYPE PLUMBING
J 0
(-225 1250);
DISPLAY 0.872340 (-225 1250);
PAINT GREEN (-225 1250);
DISPLAY INVISIBLE (-225 1250);
FORCEPROP 1 LAST HDL_TAP TRUE
J 0
(100 1075);
DISPLAY 0.872340 (100 1075);
DISPLAY INVISIBLE (100 1075);
FORCEPROP 1 LAST PATH I38
J 0
(-227 1200);
DISPLAY 0.872340 (-227 1200);
PAINT GREEN (-227 1200);
DISPLAY INVISIBLE (-227 1200);
FORCEADD TAP..1
(-225 1250);
FORCEPROP 3 LASTPIN (-275 1250) SIG_NAME M_A_CPU1_SB_DQ<13>
J 0
(-265 1260);
DISPLAY 0.659574 (-265 1260);
PAINT MONO (-265 1260);
DISPLAY INVISIBLE (-265 1260);
FORCEPROP 1 LASTPIN (-275 1250) BN 13
J 0
(-287 1258);
DISPLAY 0.680851 (-287 1258);
PAINT GREEN (-287 1258);
FORCEPROP 2 LAST CDS_LIB standard
J 0
(-225 1250);
PAINT MONO (-225 1250);
DISPLAY INVISIBLE (-225 1250);
FORCEPROP 1 LAST BODY_TYPE PLUMBING
J 0
(-225 1300);
DISPLAY 0.872340 (-225 1300);
PAINT GREEN (-225 1300);
DISPLAY INVISIBLE (-225 1300);
FORCEPROP 1 LAST HDL_TAP TRUE
J 0
(100 1125);
DISPLAY 0.872340 (100 1125);
DISPLAY INVISIBLE (100 1125);
FORCEPROP 1 LAST PATH I39
J 0
(-227 1250);
DISPLAY 0.872340 (-227 1250);
PAINT GREEN (-227 1250);
DISPLAY INVISIBLE (-227 1250);
FORCEADD OFFPAGE..2
R 2
(-2800 350);
FORCEPROP 2 LAST $XR0 51 
J 0
(-3024 350);
DISPLAY 0.638298 (-3024 350);
PAINT MONO (-3024 350);
FORCEPROP 2 LAST CDS_LIB standard
J 0
(-2800 350);
PAINT MONO (-2800 350);
DISPLAY INVISIBLE (-2800 350);
FORCEPROP 1 LAST OFFPAGE TRUE
J 2
(-3125 225);
DISPLAY 0.872340 (-3125 225);
DISPLAY INVISIBLE (-3125 225);
FORCEPROP 1 LAST COMMENT_BODY TRUE
J 2
(-2755 255);
DISPLAY 0.872340 (-2755 255);
PAINT GREEN (-2755 255);
DISPLAY INVISIBLE (-2755 255);
FORCEPROP 2 LAST PATH I4
J 0
(-2750 425);
DISPLAY 1.021277 (-2750 425);
DISPLAY INVISIBLE (-2750 425);
FORCEADD TAP..1
(-225 1350);
FORCEPROP 3 LASTPIN (-275 1350) SIG_NAME M_A_CPU1_SB_DQ<15>
J 0
(-265 1360);
DISPLAY 0.659574 (-265 1360);
PAINT MONO (-265 1360);
DISPLAY INVISIBLE (-265 1360);
FORCEPROP 1 LASTPIN (-275 1350) BN 15
J 0
(-287 1358);
DISPLAY 0.680851 (-287 1358);
PAINT GREEN (-287 1358);
FORCEPROP 2 LAST CDS_LIB standard
J 0
(-225 1350);
PAINT MONO (-225 1350);
DISPLAY INVISIBLE (-225 1350);
FORCEPROP 1 LAST BODY_TYPE PLUMBING
J 0
(-225 1400);
DISPLAY 0.872340 (-225 1400);
PAINT GREEN (-225 1400);
DISPLAY INVISIBLE (-225 1400);
FORCEPROP 1 LAST HDL_TAP TRUE
J 0
(100 1225);
DISPLAY 0.872340 (100 1225);
DISPLAY INVISIBLE (100 1225);
FORCEPROP 1 LAST PATH I40
J 0
(-227 1350);
DISPLAY 0.872340 (-227 1350);
PAINT GREEN (-227 1350);
DISPLAY INVISIBLE (-227 1350);
FORCEADD TAP..1
(-225 1300);
FORCEPROP 3 LASTPIN (-275 1300) SIG_NAME M_A_CPU1_SB_DQ<14>
J 0
(-265 1310);
DISPLAY 0.659574 (-265 1310);
PAINT MONO (-265 1310);
DISPLAY INVISIBLE (-265 1310);
FORCEPROP 1 LASTPIN (-275 1300) BN 14
J 0
(-287 1308);
DISPLAY 0.680851 (-287 1308);
PAINT GREEN (-287 1308);
FORCEPROP 2 LAST CDS_LIB standard
J 0
(-225 1300);
PAINT MONO (-225 1300);
DISPLAY INVISIBLE (-225 1300);
FORCEPROP 1 LAST BODY_TYPE PLUMBING
J 0
(-225 1350);
DISPLAY 0.872340 (-225 1350);
PAINT GREEN (-225 1350);
DISPLAY INVISIBLE (-225 1350);
FORCEPROP 1 LAST HDL_TAP TRUE
J 0
(100 1175);
DISPLAY 0.872340 (100 1175);
DISPLAY INVISIBLE (100 1175);
FORCEPROP 1 LAST PATH I41
J 0
(-227 1300);
DISPLAY 0.872340 (-227 1300);
PAINT GREEN (-227 1300);
DISPLAY INVISIBLE (-227 1300);
FORCEADD TAP..1
(-225 1450);
FORCEPROP 3 LASTPIN (-275 1450) SIG_NAME M_A_CPU1_SB_DQ<17>
J 0
(-265 1460);
DISPLAY 0.659574 (-265 1460);
PAINT MONO (-265 1460);
DISPLAY INVISIBLE (-265 1460);
FORCEPROP 1 LASTPIN (-275 1450) BN 17
J 0
(-287 1458);
DISPLAY 0.680851 (-287 1458);
PAINT GREEN (-287 1458);
FORCEPROP 2 LAST CDS_LIB standard
J 0
(-225 1450);
PAINT MONO (-225 1450);
DISPLAY INVISIBLE (-225 1450);
FORCEPROP 1 LAST BODY_TYPE PLUMBING
J 0
(-225 1500);
DISPLAY 0.872340 (-225 1500);
PAINT GREEN (-225 1500);
DISPLAY INVISIBLE (-225 1500);
FORCEPROP 1 LAST HDL_TAP TRUE
J 0
(100 1325);
DISPLAY 0.872340 (100 1325);
DISPLAY INVISIBLE (100 1325);
FORCEPROP 1 LAST PATH I42
J 0
(-227 1450);
DISPLAY 0.872340 (-227 1450);
PAINT GREEN (-227 1450);
DISPLAY INVISIBLE (-227 1450);
FORCEADD TAP..1
(-225 1400);
FORCEPROP 3 LASTPIN (-275 1400) SIG_NAME M_A_CPU1_SB_DQ<16>
J 0
(-265 1410);
DISPLAY 0.659574 (-265 1410);
PAINT MONO (-265 1410);
DISPLAY INVISIBLE (-265 1410);
FORCEPROP 1 LASTPIN (-275 1400) BN 16
J 0
(-287 1408);
DISPLAY 0.680851 (-287 1408);
PAINT GREEN (-287 1408);
FORCEPROP 2 LAST CDS_LIB standard
J 0
(-225 1400);
PAINT MONO (-225 1400);
DISPLAY INVISIBLE (-225 1400);
FORCEPROP 1 LAST BODY_TYPE PLUMBING
J 0
(-225 1450);
DISPLAY 0.872340 (-225 1450);
PAINT GREEN (-225 1450);
DISPLAY INVISIBLE (-225 1450);
FORCEPROP 1 LAST HDL_TAP TRUE
J 0
(100 1275);
DISPLAY 0.872340 (100 1275);
DISPLAY INVISIBLE (100 1275);
FORCEPROP 1 LAST PATH I43
J 0
(-227 1400);
DISPLAY 0.872340 (-227 1400);
PAINT GREEN (-227 1400);
DISPLAY INVISIBLE (-227 1400);
FORCEADD TAP..1
(-225 1500);
FORCEPROP 3 LASTPIN (-275 1500) SIG_NAME M_A_CPU1_SB_DQ<18>
J 0
(-265 1510);
DISPLAY 0.659574 (-265 1510);
PAINT MONO (-265 1510);
DISPLAY INVISIBLE (-265 1510);
FORCEPROP 1 LASTPIN (-275 1500) BN 18
J 0
(-287 1508);
DISPLAY 0.680851 (-287 1508);
PAINT GREEN (-287 1508);
FORCEPROP 2 LAST CDS_LIB standard
J 0
(-225 1500);
PAINT MONO (-225 1500);
DISPLAY INVISIBLE (-225 1500);
FORCEPROP 1 LAST BODY_TYPE PLUMBING
J 0
(-225 1550);
DISPLAY 0.872340 (-225 1550);
PAINT GREEN (-225 1550);
DISPLAY INVISIBLE (-225 1550);
FORCEPROP 1 LAST HDL_TAP TRUE
J 0
(100 1375);
DISPLAY 0.872340 (100 1375);
DISPLAY INVISIBLE (100 1375);
FORCEPROP 1 LAST PATH I44
J 0
(-227 1500);
DISPLAY 0.872340 (-227 1500);
PAINT GREEN (-227 1500);
DISPLAY INVISIBLE (-227 1500);
FORCEADD TAP..1
(-225 1550);
FORCEPROP 3 LASTPIN (-275 1550) SIG_NAME M_A_CPU1_SB_DQ<19>
J 0
(-265 1560);
DISPLAY 0.659574 (-265 1560);
PAINT MONO (-265 1560);
DISPLAY INVISIBLE (-265 1560);
FORCEPROP 1 LASTPIN (-275 1550) BN 19
J 0
(-287 1558);
DISPLAY 0.680851 (-287 1558);
PAINT GREEN (-287 1558);
FORCEPROP 2 LAST CDS_LIB standard
J 0
(-225 1550);
PAINT MONO (-225 1550);
DISPLAY INVISIBLE (-225 1550);
FORCEPROP 1 LAST BODY_TYPE PLUMBING
J 0
(-225 1600);
DISPLAY 0.872340 (-225 1600);
PAINT GREEN (-225 1600);
DISPLAY INVISIBLE (-225 1600);
FORCEPROP 1 LAST HDL_TAP TRUE
J 0
(100 1425);
DISPLAY 0.872340 (100 1425);
DISPLAY INVISIBLE (100 1425);
FORCEPROP 1 LAST PATH I45
J 0
(-227 1550);
DISPLAY 0.872340 (-227 1550);
PAINT GREEN (-227 1550);
DISPLAY INVISIBLE (-227 1550);
FORCEADD TAP..1
(-225 1600);
FORCEPROP 3 LASTPIN (-275 1600) SIG_NAME M_A_CPU1_SB_DQ<20>
J 0
(-265 1610);
DISPLAY 0.659574 (-265 1610);
PAINT MONO (-265 1610);
DISPLAY INVISIBLE (-265 1610);
FORCEPROP 1 LASTPIN (-275 1600) BN 20
J 0
(-287 1608);
DISPLAY 0.680851 (-287 1608);
PAINT GREEN (-287 1608);
FORCEPROP 2 LAST CDS_LIB standard
J 0
(-225 1600);
PAINT MONO (-225 1600);
DISPLAY INVISIBLE (-225 1600);
FORCEPROP 1 LAST BODY_TYPE PLUMBING
J 0
(-225 1650);
DISPLAY 0.872340 (-225 1650);
PAINT GREEN (-225 1650);
DISPLAY INVISIBLE (-225 1650);
FORCEPROP 1 LAST HDL_TAP TRUE
J 0
(100 1475);
DISPLAY 0.872340 (100 1475);
DISPLAY INVISIBLE (100 1475);
FORCEPROP 1 LAST PATH I46
J 0
(-227 1600);
DISPLAY 0.872340 (-227 1600);
PAINT GREEN (-227 1600);
DISPLAY INVISIBLE (-227 1600);
FORCEADD TAP..1
R 2
(-1875 1650);
FORCEPROP 3 LASTPIN (-1825 1650) SIG_NAME M_A_CPU1_SB_CB<1>
J 0
(-1815 1660);
DISPLAY 0.659574 (-1815 1660);
PAINT MONO (-1815 1660);
DISPLAY INVISIBLE (-1815 1660);
FORCEPROP 1 LASTPIN (-1825 1650) BN 1
J 2
(-1813 1658);
DISPLAY 0.680851 (-1813 1658);
PAINT GREEN (-1813 1658);
FORCEPROP 2 LAST CDS_LIB standard
J 0
(-1875 1650);
DISPLAY INVISIBLE (-1875 1650);
FORCEPROP 1 LAST BODY_TYPE PLUMBING
J 2
(-1875 1700);
DISPLAY 0.872340 (-1875 1700);
PAINT GREEN (-1875 1700);
DISPLAY INVISIBLE (-1875 1700);
FORCEPROP 1 LAST HDL_TAP TRUE
J 2
(-2200 1525);
DISPLAY 0.872340 (-2200 1525);
DISPLAY INVISIBLE (-2200 1525);
FORCEPROP 1 LAST PATH I47
J 2
(-1873 1650);
DISPLAY 0.872340 (-1873 1650);
PAINT GREEN (-1873 1650);
DISPLAY INVISIBLE (-1873 1650);
FORCEADD TAP..1
R 2
(-1875 1700);
FORCEPROP 3 LASTPIN (-1825 1700) SIG_NAME M_A_CPU1_SB_CB<2>
J 0
(-1815 1710);
DISPLAY 0.659574 (-1815 1710);
PAINT MONO (-1815 1710);
DISPLAY INVISIBLE (-1815 1710);
FORCEPROP 1 LASTPIN (-1825 1700) BN 2
J 2
(-1813 1708);
DISPLAY 0.680851 (-1813 1708);
PAINT GREEN (-1813 1708);
FORCEPROP 2 LAST CDS_LIB standard
J 0
(-1875 1700);
DISPLAY INVISIBLE (-1875 1700);
FORCEPROP 1 LAST BODY_TYPE PLUMBING
J 2
(-1875 1750);
DISPLAY 0.872340 (-1875 1750);
PAINT GREEN (-1875 1750);
DISPLAY INVISIBLE (-1875 1750);
FORCEPROP 1 LAST HDL_TAP TRUE
J 2
(-2200 1575);
DISPLAY 0.872340 (-2200 1575);
DISPLAY INVISIBLE (-2200 1575);
FORCEPROP 1 LAST PATH I48
J 2
(-1873 1700);
DISPLAY 0.872340 (-1873 1700);
PAINT GREEN (-1873 1700);
DISPLAY INVISIBLE (-1873 1700);
FORCEADD TAP..1
R 2
(-1875 1750);
FORCEPROP 3 LASTPIN (-1825 1750) SIG_NAME M_A_CPU1_SB_CB<3>
J 0
(-1815 1760);
DISPLAY 0.659574 (-1815 1760);
PAINT MONO (-1815 1760);
DISPLAY INVISIBLE (-1815 1760);
FORCEPROP 1 LASTPIN (-1825 1750) BN 3
J 2
(-1813 1758);
DISPLAY 0.680851 (-1813 1758);
PAINT GREEN (-1813 1758);
FORCEPROP 2 LAST CDS_LIB standard
J 0
(-1875 1750);
DISPLAY INVISIBLE (-1875 1750);
FORCEPROP 1 LAST BODY_TYPE PLUMBING
J 2
(-1875 1800);
DISPLAY 0.872340 (-1875 1800);
PAINT GREEN (-1875 1800);
DISPLAY INVISIBLE (-1875 1800);
FORCEPROP 1 LAST HDL_TAP TRUE
J 2
(-2200 1625);
DISPLAY 0.872340 (-2200 1625);
DISPLAY INVISIBLE (-2200 1625);
FORCEPROP 1 LAST PATH I49
J 2
(-1873 1750);
DISPLAY 0.872340 (-1873 1750);
PAINT GREEN (-1873 1750);
DISPLAY INVISIBLE (-1873 1750);
FORCEADD OFFPAGE..2
R 2
(-2800 400);
FORCEPROP 2 LAST $XR0 51 
J 0
(-3024 400);
DISPLAY 0.638298 (-3024 400);
PAINT MONO (-3024 400);
FORCEPROP 2 LAST CDS_LIB standard
J 0
(-2800 400);
PAINT MONO (-2800 400);
DISPLAY INVISIBLE (-2800 400);
FORCEPROP 1 LAST OFFPAGE TRUE
J 2
(-3125 275);
DISPLAY 0.872340 (-3125 275);
DISPLAY INVISIBLE (-3125 275);
FORCEPROP 1 LAST COMMENT_BODY TRUE
J 2
(-2755 305);
DISPLAY 0.872340 (-2755 305);
PAINT GREEN (-2755 305);
DISPLAY INVISIBLE (-2755 305);
FORCEPROP 2 LAST PATH I5
J 0
(-2750 475);
DISPLAY 1.021277 (-2750 475);
DISPLAY INVISIBLE (-2750 475);
FORCEADD TAP..1
R 2
(-1875 1800);
FORCEPROP 3 LASTPIN (-1825 1800) SIG_NAME M_A_CPU1_SB_CB<4>
J 0
(-1815 1810);
DISPLAY 0.659574 (-1815 1810);
PAINT MONO (-1815 1810);
DISPLAY INVISIBLE (-1815 1810);
FORCEPROP 1 LASTPIN (-1825 1800) BN 4
J 2
(-1813 1808);
DISPLAY 0.680851 (-1813 1808);
PAINT GREEN (-1813 1808);
FORCEPROP 2 LAST CDS_LIB standard
J 0
(-1875 1800);
DISPLAY INVISIBLE (-1875 1800);
FORCEPROP 1 LAST BODY_TYPE PLUMBING
J 2
(-1875 1850);
DISPLAY 0.872340 (-1875 1850);
PAINT GREEN (-1875 1850);
DISPLAY INVISIBLE (-1875 1850);
FORCEPROP 1 LAST HDL_TAP TRUE
J 2
(-2200 1675);
DISPLAY 0.872340 (-2200 1675);
DISPLAY INVISIBLE (-2200 1675);
FORCEPROP 1 LAST PATH I50
J 2
(-1873 1800);
DISPLAY 0.872340 (-1873 1800);
PAINT GREEN (-1873 1800);
DISPLAY INVISIBLE (-1873 1800);
FORCEADD TAP..1
R 2
(-1875 1850);
FORCEPROP 3 LASTPIN (-1825 1850) SIG_NAME M_A_CPU1_SB_CB<5>
J 0
(-1815 1860);
DISPLAY 0.659574 (-1815 1860);
PAINT MONO (-1815 1860);
DISPLAY INVISIBLE (-1815 1860);
FORCEPROP 1 LASTPIN (-1825 1850) BN 5
J 2
(-1813 1858);
DISPLAY 0.680851 (-1813 1858);
PAINT GREEN (-1813 1858);
FORCEPROP 2 LAST CDS_LIB standard
J 0
(-1875 1850);
DISPLAY INVISIBLE (-1875 1850);
FORCEPROP 1 LAST BODY_TYPE PLUMBING
J 2
(-1875 1900);
DISPLAY 0.872340 (-1875 1900);
PAINT GREEN (-1875 1900);
DISPLAY INVISIBLE (-1875 1900);
FORCEPROP 1 LAST HDL_TAP TRUE
J 2
(-2200 1725);
DISPLAY 0.872340 (-2200 1725);
DISPLAY INVISIBLE (-2200 1725);
FORCEPROP 1 LAST PATH I51
J 2
(-1873 1850);
DISPLAY 0.872340 (-1873 1850);
PAINT GREEN (-1873 1850);
DISPLAY INVISIBLE (-1873 1850);
FORCEADD TAP..1
R 2
(-1875 1900);
FORCEPROP 3 LASTPIN (-1825 1900) SIG_NAME M_A_CPU1_SB_CB<6>
J 0
(-1815 1910);
DISPLAY 0.659574 (-1815 1910);
PAINT MONO (-1815 1910);
DISPLAY INVISIBLE (-1815 1910);
FORCEPROP 1 LASTPIN (-1825 1900) BN 6
J 2
(-1813 1908);
DISPLAY 0.680851 (-1813 1908);
PAINT GREEN (-1813 1908);
FORCEPROP 2 LAST CDS_LIB standard
J 0
(-1875 1900);
DISPLAY INVISIBLE (-1875 1900);
FORCEPROP 1 LAST BODY_TYPE PLUMBING
J 2
(-1875 1950);
DISPLAY 0.872340 (-1875 1950);
PAINT GREEN (-1875 1950);
DISPLAY INVISIBLE (-1875 1950);
FORCEPROP 1 LAST HDL_TAP TRUE
J 2
(-2200 1775);
DISPLAY 0.872340 (-2200 1775);
DISPLAY INVISIBLE (-2200 1775);
FORCEPROP 1 LAST PATH I52
J 2
(-1873 1900);
DISPLAY 0.872340 (-1873 1900);
PAINT GREEN (-1873 1900);
DISPLAY INVISIBLE (-1873 1900);
FORCEADD TAP..1
R 2
(-1875 1950);
FORCEPROP 3 LASTPIN (-1825 1950) SIG_NAME M_A_CPU1_SB_CB<7>
J 0
(-1815 1960);
DISPLAY 0.659574 (-1815 1960);
PAINT MONO (-1815 1960);
DISPLAY INVISIBLE (-1815 1960);
FORCEPROP 1 LASTPIN (-1825 1950) BN 7
J 2
(-1813 1958);
DISPLAY 0.680851 (-1813 1958);
PAINT GREEN (-1813 1958);
FORCEPROP 2 LAST CDS_LIB standard
J 0
(-1875 1950);
DISPLAY INVISIBLE (-1875 1950);
FORCEPROP 1 LAST BODY_TYPE PLUMBING
J 2
(-1875 2000);
DISPLAY 0.872340 (-1875 2000);
PAINT GREEN (-1875 2000);
DISPLAY INVISIBLE (-1875 2000);
FORCEPROP 1 LAST HDL_TAP TRUE
J 2
(-2200 1825);
DISPLAY 0.872340 (-2200 1825);
DISPLAY INVISIBLE (-2200 1825);
FORCEPROP 1 LAST PATH I53
J 2
(-1873 1950);
DISPLAY 0.872340 (-1873 1950);
PAINT GREEN (-1873 1950);
DISPLAY INVISIBLE (-1873 1950);
FORCEADD TAP..1
R 2
(-1875 2050);
FORCEPROP 3 LASTPIN (-1825 2050) SIG_NAME M_A_CPU1_SA_CB<0>
J 0
(-1815 2060);
DISPLAY 0.659574 (-1815 2060);
PAINT MONO (-1815 2060);
DISPLAY INVISIBLE (-1815 2060);
FORCEPROP 1 LASTPIN (-1825 2050) BN 0
J 2
(-1813 2058);
DISPLAY 0.680851 (-1813 2058);
PAINT GREEN (-1813 2058);
FORCEPROP 2 LAST CDS_LIB standard
J 0
(-1875 2050);
PAINT MONO (-1875 2050);
DISPLAY INVISIBLE (-1875 2050);
FORCEPROP 1 LAST BODY_TYPE PLUMBING
J 2
(-1875 2100);
DISPLAY 0.872340 (-1875 2100);
PAINT GREEN (-1875 2100);
DISPLAY INVISIBLE (-1875 2100);
FORCEPROP 1 LAST HDL_TAP TRUE
J 2
(-2200 1925);
DISPLAY 0.872340 (-2200 1925);
DISPLAY INVISIBLE (-2200 1925);
FORCEPROP 1 LAST PATH I54
J 2
(-1873 2050);
DISPLAY 0.872340 (-1873 2050);
PAINT GREEN (-1873 2050);
DISPLAY INVISIBLE (-1873 2050);
FORCEADD TAP..1
R 2
(-1875 2100);
FORCEPROP 3 LASTPIN (-1825 2100) SIG_NAME M_A_CPU1_SA_CB<1>
J 0
(-1815 2110);
DISPLAY 0.659574 (-1815 2110);
PAINT MONO (-1815 2110);
DISPLAY INVISIBLE (-1815 2110);
FORCEPROP 1 LASTPIN (-1825 2100) BN 1
J 2
(-1813 2108);
DISPLAY 0.680851 (-1813 2108);
PAINT GREEN (-1813 2108);
FORCEPROP 2 LAST CDS_LIB standard
J 0
(-1875 2100);
DISPLAY INVISIBLE (-1875 2100);
FORCEPROP 1 LAST BODY_TYPE PLUMBING
J 2
(-1875 2150);
DISPLAY 0.872340 (-1875 2150);
PAINT GREEN (-1875 2150);
DISPLAY INVISIBLE (-1875 2150);
FORCEPROP 1 LAST HDL_TAP TRUE
J 2
(-2200 1975);
DISPLAY 0.872340 (-2200 1975);
DISPLAY INVISIBLE (-2200 1975);
FORCEPROP 1 LAST PATH I55
J 2
(-1873 2100);
DISPLAY 0.872340 (-1873 2100);
PAINT GREEN (-1873 2100);
DISPLAY INVISIBLE (-1873 2100);
FORCEADD TAP..1
R 2
(-1875 2150);
FORCEPROP 3 LASTPIN (-1825 2150) SIG_NAME M_A_CPU1_SA_CB<2>
J 0
(-1815 2160);
DISPLAY 0.659574 (-1815 2160);
PAINT MONO (-1815 2160);
DISPLAY INVISIBLE (-1815 2160);
FORCEPROP 1 LASTPIN (-1825 2150) BN 2
J 2
(-1813 2158);
DISPLAY 0.680851 (-1813 2158);
PAINT GREEN (-1813 2158);
FORCEPROP 2 LAST CDS_LIB standard
J 0
(-1875 2150);
DISPLAY INVISIBLE (-1875 2150);
FORCEPROP 1 LAST BODY_TYPE PLUMBING
J 2
(-1875 2200);
DISPLAY 0.872340 (-1875 2200);
PAINT GREEN (-1875 2200);
DISPLAY INVISIBLE (-1875 2200);
FORCEPROP 1 LAST HDL_TAP TRUE
J 2
(-2200 2025);
DISPLAY 0.872340 (-2200 2025);
DISPLAY INVISIBLE (-2200 2025);
FORCEPROP 1 LAST PATH I56
J 2
(-1873 2150);
DISPLAY 0.872340 (-1873 2150);
PAINT GREEN (-1873 2150);
DISPLAY INVISIBLE (-1873 2150);
FORCEADD TAP..1
R 2
(-1875 2250);
FORCEPROP 3 LASTPIN (-1825 2250) SIG_NAME M_A_CPU1_SA_CB<4>
J 0
(-1815 2260);
DISPLAY 0.659574 (-1815 2260);
PAINT MONO (-1815 2260);
DISPLAY INVISIBLE (-1815 2260);
FORCEPROP 1 LASTPIN (-1825 2250) BN 4
J 2
(-1813 2258);
DISPLAY 0.680851 (-1813 2258);
PAINT GREEN (-1813 2258);
FORCEPROP 2 LAST CDS_LIB standard
J 0
(-1875 2250);
DISPLAY INVISIBLE (-1875 2250);
FORCEPROP 1 LAST BODY_TYPE PLUMBING
J 2
(-1875 2300);
DISPLAY 0.872340 (-1875 2300);
PAINT GREEN (-1875 2300);
DISPLAY INVISIBLE (-1875 2300);
FORCEPROP 1 LAST HDL_TAP TRUE
J 2
(-2200 2125);
DISPLAY 0.872340 (-2200 2125);
DISPLAY INVISIBLE (-2200 2125);
FORCEPROP 1 LAST PATH I57
J 2
(-1873 2250);
DISPLAY 0.872340 (-1873 2250);
PAINT GREEN (-1873 2250);
DISPLAY INVISIBLE (-1873 2250);
FORCEADD TAP..1
R 2
(-1875 2200);
FORCEPROP 3 LASTPIN (-1825 2200) SIG_NAME M_A_CPU1_SA_CB<3>
J 0
(-1815 2210);
DISPLAY 0.659574 (-1815 2210);
PAINT MONO (-1815 2210);
DISPLAY INVISIBLE (-1815 2210);
FORCEPROP 1 LASTPIN (-1825 2200) BN 3
J 2
(-1813 2208);
DISPLAY 0.680851 (-1813 2208);
PAINT GREEN (-1813 2208);
FORCEPROP 2 LAST CDS_LIB standard
J 0
(-1875 2200);
DISPLAY INVISIBLE (-1875 2200);
FORCEPROP 1 LAST BODY_TYPE PLUMBING
J 2
(-1875 2250);
DISPLAY 0.872340 (-1875 2250);
PAINT GREEN (-1875 2250);
DISPLAY INVISIBLE (-1875 2250);
FORCEPROP 1 LAST HDL_TAP TRUE
J 2
(-2200 2075);
DISPLAY 0.872340 (-2200 2075);
DISPLAY INVISIBLE (-2200 2075);
FORCEPROP 1 LAST PATH I58
J 2
(-1873 2200);
DISPLAY 0.872340 (-1873 2200);
PAINT GREEN (-1873 2200);
DISPLAY INVISIBLE (-1873 2200);
FORCEADD TAP..1
R 2
(-1875 2300);
FORCEPROP 3 LASTPIN (-1825 2300) SIG_NAME M_A_CPU1_SA_CB<5>
J 0
(-1815 2310);
DISPLAY 0.659574 (-1815 2310);
PAINT MONO (-1815 2310);
DISPLAY INVISIBLE (-1815 2310);
FORCEPROP 1 LASTPIN (-1825 2300) BN 5
J 2
(-1813 2308);
DISPLAY 0.680851 (-1813 2308);
PAINT GREEN (-1813 2308);
FORCEPROP 2 LAST CDS_LIB standard
J 0
(-1875 2300);
DISPLAY INVISIBLE (-1875 2300);
FORCEPROP 1 LAST BODY_TYPE PLUMBING
J 2
(-1875 2350);
DISPLAY 0.872340 (-1875 2350);
PAINT GREEN (-1875 2350);
DISPLAY INVISIBLE (-1875 2350);
FORCEPROP 1 LAST HDL_TAP TRUE
J 2
(-2200 2175);
DISPLAY 0.872340 (-2200 2175);
DISPLAY INVISIBLE (-2200 2175);
FORCEPROP 1 LAST PATH I59
J 2
(-1873 2300);
DISPLAY 0.872340 (-1873 2300);
PAINT GREEN (-1873 2300);
DISPLAY INVISIBLE (-1873 2300);
FORCEADD OFFPAGE..3
R 2
(-2800 950);
FORCEPROP 2 LAST $XR0 114 
J 0
(-3080 950);
DISPLAY 0.638298 (-3080 950);
PAINT MONO (-3080 950);
FORCEPROP 2 LAST CDS_LIB standard
J 0
(-2800 950);
PAINT MONO (-2800 950);
DISPLAY INVISIBLE (-2800 950);
FORCEPROP 1 LAST OFFPAGE TRUE
J 2
(-3125 825);
DISPLAY 0.872340 (-3125 825);
DISPLAY INVISIBLE (-3125 825);
FORCEPROP 1 LAST COMMENT_BODY TRUE
J 2
(-2750 850);
DISPLAY 0.872340 (-2750 850);
PAINT GREEN (-2750 850);
DISPLAY INVISIBLE (-2750 850);
FORCEPROP 2 LAST PATH I6
J 0
(-2750 1025);
DISPLAY 1.021277 (-2750 1025);
DISPLAY INVISIBLE (-2750 1025);
FORCEADD TAP..1
R 2
(-1875 2350);
FORCEPROP 3 LASTPIN (-1825 2350) SIG_NAME M_A_CPU1_SA_CB<6>
J 0
(-1815 2360);
DISPLAY 0.659574 (-1815 2360);
PAINT MONO (-1815 2360);
DISPLAY INVISIBLE (-1815 2360);
FORCEPROP 1 LASTPIN (-1825 2350) BN 6
J 2
(-1813 2358);
DISPLAY 0.680851 (-1813 2358);
PAINT GREEN (-1813 2358);
FORCEPROP 2 LAST CDS_LIB standard
J 0
(-1875 2350);
DISPLAY INVISIBLE (-1875 2350);
FORCEPROP 1 LAST BODY_TYPE PLUMBING
J 2
(-1875 2400);
DISPLAY 0.872340 (-1875 2400);
PAINT GREEN (-1875 2400);
DISPLAY INVISIBLE (-1875 2400);
FORCEPROP 1 LAST HDL_TAP TRUE
J 2
(-2200 2225);
DISPLAY 0.872340 (-2200 2225);
DISPLAY INVISIBLE (-2200 2225);
FORCEPROP 1 LAST PATH I60
J 2
(-1873 2350);
DISPLAY 0.872340 (-1873 2350);
PAINT GREEN (-1873 2350);
DISPLAY INVISIBLE (-1873 2350);
FORCEADD TAP..1
R 2
(-1875 2400);
FORCEPROP 3 LASTPIN (-1825 2400) SIG_NAME M_A_CPU1_SA_CB<7>
J 0
(-1815 2410);
DISPLAY 0.659574 (-1815 2410);
PAINT MONO (-1815 2410);
DISPLAY INVISIBLE (-1815 2410);
FORCEPROP 1 LASTPIN (-1825 2400) BN 7
J 2
(-1813 2408);
DISPLAY 0.680851 (-1813 2408);
PAINT GREEN (-1813 2408);
FORCEPROP 2 LAST CDS_LIB standard
J 0
(-1875 2400);
DISPLAY INVISIBLE (-1875 2400);
FORCEPROP 1 LAST BODY_TYPE PLUMBING
J 2
(-1875 2450);
DISPLAY 0.872340 (-1875 2450);
PAINT GREEN (-1875 2450);
DISPLAY INVISIBLE (-1875 2450);
FORCEPROP 1 LAST HDL_TAP TRUE
J 2
(-2200 2275);
DISPLAY 0.872340 (-2200 2275);
DISPLAY INVISIBLE (-2200 2275);
FORCEPROP 1 LAST PATH I61
J 2
(-1873 2400);
DISPLAY 0.872340 (-1873 2400);
PAINT GREEN (-1873 2400);
DISPLAY INVISIBLE (-1873 2400);
FORCEADD TAP..1
R 2
(-1875 3150);
FORCEPROP 3 LASTPIN (-1825 3150) SIG_NAME M_A_CPU1_SB_CA<1>
J 0
(-1815 3160);
DISPLAY 0.659574 (-1815 3160);
PAINT MONO (-1815 3160);
DISPLAY INVISIBLE (-1815 3160);
FORCEPROP 1 LASTPIN (-1825 3150) BN 1
J 2
(-1813 3158);
DISPLAY 0.680851 (-1813 3158);
PAINT GREEN (-1813 3158);
FORCEPROP 2 LAST CDS_LIB standard
J 0
(-1875 3150);
DISPLAY INVISIBLE (-1875 3150);
FORCEPROP 1 LAST BODY_TYPE PLUMBING
J 2
(-1875 3200);
DISPLAY 0.872340 (-1875 3200);
PAINT GREEN (-1875 3200);
DISPLAY INVISIBLE (-1875 3200);
FORCEPROP 1 LAST HDL_TAP TRUE
J 2
(-2200 3025);
DISPLAY 0.872340 (-2200 3025);
DISPLAY INVISIBLE (-2200 3025);
FORCEPROP 1 LAST PATH I62
J 2
(-1873 3150);
DISPLAY 0.872340 (-1873 3150);
PAINT GREEN (-1873 3150);
DISPLAY INVISIBLE (-1873 3150);
FORCEADD TAP..1
R 2
(-1875 3100);
FORCEPROP 3 LASTPIN (-1825 3100) SIG_NAME M_A_CPU1_SB_CA<0>
J 0
(-1815 3110);
DISPLAY 0.659574 (-1815 3110);
PAINT MONO (-1815 3110);
DISPLAY INVISIBLE (-1815 3110);
FORCEPROP 1 LASTPIN (-1825 3100) BN 0
J 2
(-1813 3108);
DISPLAY 0.680851 (-1813 3108);
PAINT GREEN (-1813 3108);
FORCEPROP 2 LAST CDS_LIB standard
J 0
(-1875 3100);
DISPLAY INVISIBLE (-1875 3100);
FORCEPROP 1 LAST BODY_TYPE PLUMBING
J 2
(-1875 3150);
DISPLAY 0.872340 (-1875 3150);
PAINT GREEN (-1875 3150);
DISPLAY INVISIBLE (-1875 3150);
FORCEPROP 1 LAST HDL_TAP TRUE
J 2
(-2200 2975);
DISPLAY 0.872340 (-2200 2975);
DISPLAY INVISIBLE (-2200 2975);
FORCEPROP 1 LAST PATH I63
J 2
(-1873 3100);
DISPLAY 0.872340 (-1873 3100);
PAINT GREEN (-1873 3100);
DISPLAY INVISIBLE (-1873 3100);
FORCEADD TAP..1
R 2
(-1875 3200);
FORCEPROP 3 LASTPIN (-1825 3200) SIG_NAME M_A_CPU1_SB_CA<2>
J 0
(-1815 3210);
DISPLAY 0.659574 (-1815 3210);
PAINT MONO (-1815 3210);
DISPLAY INVISIBLE (-1815 3210);
FORCEPROP 1 LASTPIN (-1825 3200) BN 2
J 2
(-1813 3208);
DISPLAY 0.680851 (-1813 3208);
PAINT GREEN (-1813 3208);
FORCEPROP 2 LAST CDS_LIB standard
J 0
(-1875 3200);
DISPLAY INVISIBLE (-1875 3200);
FORCEPROP 1 LAST BODY_TYPE PLUMBING
J 2
(-1875 3250);
DISPLAY 0.872340 (-1875 3250);
PAINT GREEN (-1875 3250);
DISPLAY INVISIBLE (-1875 3250);
FORCEPROP 1 LAST HDL_TAP TRUE
J 2
(-2200 3075);
DISPLAY 0.872340 (-2200 3075);
DISPLAY INVISIBLE (-2200 3075);
FORCEPROP 1 LAST PATH I64
J 2
(-1873 3200);
DISPLAY 0.872340 (-1873 3200);
PAINT GREEN (-1873 3200);
DISPLAY INVISIBLE (-1873 3200);
FORCEADD TAP..1
R 2
(-1875 3250);
FORCEPROP 3 LASTPIN (-1825 3250) SIG_NAME M_A_CPU1_SB_CA<3>
J 0
(-1815 3260);
DISPLAY 0.659574 (-1815 3260);
PAINT MONO (-1815 3260);
DISPLAY INVISIBLE (-1815 3260);
FORCEPROP 1 LASTPIN (-1825 3250) BN 3
J 2
(-1813 3258);
DISPLAY 0.680851 (-1813 3258);
PAINT GREEN (-1813 3258);
FORCEPROP 2 LAST CDS_LIB standard
J 0
(-1875 3250);
DISPLAY INVISIBLE (-1875 3250);
FORCEPROP 1 LAST BODY_TYPE PLUMBING
J 2
(-1875 3300);
DISPLAY 0.872340 (-1875 3300);
PAINT GREEN (-1875 3300);
DISPLAY INVISIBLE (-1875 3300);
FORCEPROP 1 LAST HDL_TAP TRUE
J 2
(-2200 3125);
DISPLAY 0.872340 (-2200 3125);
DISPLAY INVISIBLE (-2200 3125);
FORCEPROP 1 LAST PATH I65
J 2
(-1873 3250);
DISPLAY 0.872340 (-1873 3250);
PAINT GREEN (-1873 3250);
DISPLAY INVISIBLE (-1873 3250);
FORCEADD TAP..1
R 2
(-1875 3300);
FORCEPROP 3 LASTPIN (-1825 3300) SIG_NAME M_A_CPU1_SB_CA<4>
J 0
(-1815 3310);
DISPLAY 0.659574 (-1815 3310);
PAINT MONO (-1815 3310);
DISPLAY INVISIBLE (-1815 3310);
FORCEPROP 1 LASTPIN (-1825 3300) BN 4
J 2
(-1813 3308);
DISPLAY 0.680851 (-1813 3308);
PAINT GREEN (-1813 3308);
FORCEPROP 2 LAST CDS_LIB standard
J 0
(-1875 3300);
DISPLAY INVISIBLE (-1875 3300);
FORCEPROP 1 LAST BODY_TYPE PLUMBING
J 2
(-1875 3350);
DISPLAY 0.872340 (-1875 3350);
PAINT GREEN (-1875 3350);
DISPLAY INVISIBLE (-1875 3350);
FORCEPROP 1 LAST HDL_TAP TRUE
J 2
(-2200 3175);
DISPLAY 0.872340 (-2200 3175);
DISPLAY INVISIBLE (-2200 3175);
FORCEPROP 1 LAST PATH I66
J 2
(-1873 3300);
DISPLAY 0.872340 (-1873 3300);
PAINT GREEN (-1873 3300);
DISPLAY INVISIBLE (-1873 3300);
FORCEADD TAP..1
R 2
(-1875 3350);
FORCEPROP 3 LASTPIN (-1825 3350) SIG_NAME M_A_CPU1_SB_CA<5>
J 0
(-1815 3360);
DISPLAY 0.659574 (-1815 3360);
PAINT MONO (-1815 3360);
DISPLAY INVISIBLE (-1815 3360);
FORCEPROP 1 LASTPIN (-1825 3350) BN 5
J 2
(-1813 3358);
DISPLAY 0.680851 (-1813 3358);
PAINT GREEN (-1813 3358);
FORCEPROP 2 LAST CDS_LIB standard
J 0
(-1875 3350);
DISPLAY INVISIBLE (-1875 3350);
FORCEPROP 1 LAST BODY_TYPE PLUMBING
J 2
(-1875 3400);
DISPLAY 0.872340 (-1875 3400);
PAINT GREEN (-1875 3400);
DISPLAY INVISIBLE (-1875 3400);
FORCEPROP 1 LAST HDL_TAP TRUE
J 2
(-2200 3225);
DISPLAY 0.872340 (-2200 3225);
DISPLAY INVISIBLE (-2200 3225);
FORCEPROP 1 LAST PATH I67
J 2
(-1873 3350);
DISPLAY 0.872340 (-1873 3350);
PAINT GREEN (-1873 3350);
DISPLAY INVISIBLE (-1873 3350);
FORCEADD TAP..1
R 2
(-1875 3400);
FORCEPROP 3 LASTPIN (-1825 3400) SIG_NAME M_A_CPU1_SB_CA<6>
J 0
(-1815 3410);
DISPLAY 0.659574 (-1815 3410);
PAINT MONO (-1815 3410);
DISPLAY INVISIBLE (-1815 3410);
FORCEPROP 1 LASTPIN (-1825 3400) BN 6
J 2
(-1813 3408);
DISPLAY 0.680851 (-1813 3408);
PAINT GREEN (-1813 3408);
FORCEPROP 2 LAST CDS_LIB standard
J 0
(-1875 3400);
DISPLAY INVISIBLE (-1875 3400);
FORCEPROP 1 LAST BODY_TYPE PLUMBING
J 2
(-1875 3450);
DISPLAY 0.872340 (-1875 3450);
PAINT GREEN (-1875 3450);
DISPLAY INVISIBLE (-1875 3450);
FORCEPROP 1 LAST HDL_TAP TRUE
J 2
(-2200 3275);
DISPLAY 0.872340 (-2200 3275);
DISPLAY INVISIBLE (-2200 3275);
FORCEPROP 1 LAST PATH I68
J 2
(-1873 3400);
DISPLAY 0.872340 (-1873 3400);
PAINT GREEN (-1873 3400);
DISPLAY INVISIBLE (-1873 3400);
FORCEADD TAP..1
R 2
(-1875 3500);
FORCEPROP 3 LASTPIN (-1825 3500) SIG_NAME M_A_CPU1_SA_CA<0>
J 0
(-1815 3510);
DISPLAY 0.659574 (-1815 3510);
PAINT MONO (-1815 3510);
DISPLAY INVISIBLE (-1815 3510);
FORCEPROP 1 LASTPIN (-1825 3500) BN 0
J 2
(-1813 3508);
DISPLAY 0.680851 (-1813 3508);
PAINT GREEN (-1813 3508);
FORCEPROP 2 LAST CDS_LIB standard
J 0
(-1875 3500);
DISPLAY INVISIBLE (-1875 3500);
FORCEPROP 1 LAST BODY_TYPE PLUMBING
J 2
(-1875 3550);
DISPLAY 0.872340 (-1875 3550);
PAINT GREEN (-1875 3550);
DISPLAY INVISIBLE (-1875 3550);
FORCEPROP 1 LAST HDL_TAP TRUE
J 2
(-2200 3375);
DISPLAY 0.872340 (-2200 3375);
DISPLAY INVISIBLE (-2200 3375);
FORCEPROP 1 LAST PATH I69
J 2
(-1873 3500);
DISPLAY 0.872340 (-1873 3500);
PAINT GREEN (-1873 3500);
DISPLAY INVISIBLE (-1873 3500);
FORCEADD OFFPAGE..1
(-2700 1300);
FORCEPROP 2 LAST $XR0 99 
J 0
(-2951 1300);
DISPLAY 0.638298 (-2951 1300);
PAINT MONO (-2951 1300);
FORCEPROP 2 LAST CDS_LIB standard
J 0
(-2700 1300);
PAINT MONO (-2700 1300);
DISPLAY INVISIBLE (-2700 1300);
FORCEPROP 1 LAST OFFPAGE TRUE
J 0
(-2375 1175);
DISPLAY 0.872340 (-2375 1175);
DISPLAY INVISIBLE (-2375 1175);
FORCEPROP 1 LAST COMMENT_BODY TRUE
J 0
(-2575 1200);
DISPLAY 0.872340 (-2575 1200);
PAINT GREEN (-2575 1200);
DISPLAY INVISIBLE (-2575 1200);
FORCEPROP 2 LAST PATH I7
J 0
(-2650 1375);
DISPLAY 1.021277 (-2650 1375);
DISPLAY INVISIBLE (-2650 1375);
FORCEADD TAP..1
R 2
(-1875 3550);
FORCEPROP 3 LASTPIN (-1825 3550) SIG_NAME M_A_CPU1_SA_CA<1>
J 0
(-1815 3560);
DISPLAY 0.659574 (-1815 3560);
PAINT MONO (-1815 3560);
DISPLAY INVISIBLE (-1815 3560);
FORCEPROP 1 LASTPIN (-1825 3550) BN 1
J 2
(-1813 3558);
DISPLAY 0.680851 (-1813 3558);
PAINT GREEN (-1813 3558);
FORCEPROP 2 LAST CDS_LIB standard
J 0
(-1875 3550);
DISPLAY INVISIBLE (-1875 3550);
FORCEPROP 1 LAST BODY_TYPE PLUMBING
J 2
(-1875 3600);
DISPLAY 0.872340 (-1875 3600);
PAINT GREEN (-1875 3600);
DISPLAY INVISIBLE (-1875 3600);
FORCEPROP 1 LAST HDL_TAP TRUE
J 2
(-2200 3425);
DISPLAY 0.872340 (-2200 3425);
DISPLAY INVISIBLE (-2200 3425);
FORCEPROP 1 LAST PATH I70
J 2
(-1873 3550);
DISPLAY 0.872340 (-1873 3550);
PAINT GREEN (-1873 3550);
DISPLAY INVISIBLE (-1873 3550);
FORCEADD TAP..1
R 2
(-1875 3650);
FORCEPROP 3 LASTPIN (-1825 3650) SIG_NAME M_A_CPU1_SA_CA<3>
J 0
(-1815 3660);
DISPLAY 0.659574 (-1815 3660);
PAINT MONO (-1815 3660);
DISPLAY INVISIBLE (-1815 3660);
FORCEPROP 1 LASTPIN (-1825 3650) BN 3
J 2
(-1813 3658);
DISPLAY 0.680851 (-1813 3658);
PAINT GREEN (-1813 3658);
FORCEPROP 2 LAST CDS_LIB standard
J 0
(-1875 3650);
DISPLAY INVISIBLE (-1875 3650);
FORCEPROP 1 LAST BODY_TYPE PLUMBING
J 2
(-1875 3700);
DISPLAY 0.872340 (-1875 3700);
PAINT GREEN (-1875 3700);
DISPLAY INVISIBLE (-1875 3700);
FORCEPROP 1 LAST HDL_TAP TRUE
J 2
(-2200 3525);
DISPLAY 0.872340 (-2200 3525);
DISPLAY INVISIBLE (-2200 3525);
FORCEPROP 1 LAST PATH I71
J 2
(-1873 3650);
DISPLAY 0.872340 (-1873 3650);
PAINT GREEN (-1873 3650);
DISPLAY INVISIBLE (-1873 3650);
FORCEADD TAP..1
R 2
(-1875 3600);
FORCEPROP 3 LASTPIN (-1825 3600) SIG_NAME M_A_CPU1_SA_CA<2>
J 0
(-1815 3610);
DISPLAY 0.659574 (-1815 3610);
PAINT MONO (-1815 3610);
DISPLAY INVISIBLE (-1815 3610);
FORCEPROP 1 LASTPIN (-1825 3600) BN 2
J 2
(-1813 3608);
DISPLAY 0.680851 (-1813 3608);
PAINT GREEN (-1813 3608);
FORCEPROP 2 LAST CDS_LIB standard
J 0
(-1875 3600);
DISPLAY INVISIBLE (-1875 3600);
FORCEPROP 1 LAST BODY_TYPE PLUMBING
J 2
(-1875 3650);
DISPLAY 0.872340 (-1875 3650);
PAINT GREEN (-1875 3650);
DISPLAY INVISIBLE (-1875 3650);
FORCEPROP 1 LAST HDL_TAP TRUE
J 2
(-2200 3475);
DISPLAY 0.872340 (-2200 3475);
DISPLAY INVISIBLE (-2200 3475);
FORCEPROP 1 LAST PATH I72
J 2
(-1873 3600);
DISPLAY 0.872340 (-1873 3600);
PAINT GREEN (-1873 3600);
DISPLAY INVISIBLE (-1873 3600);
FORCEADD TAP..1
(-225 1700);
FORCEPROP 3 LASTPIN (-275 1700) SIG_NAME M_A_CPU1_SB_DQ<22>
J 0
(-265 1710);
DISPLAY 0.659574 (-265 1710);
PAINT MONO (-265 1710);
DISPLAY INVISIBLE (-265 1710);
FORCEPROP 1 LASTPIN (-275 1700) BN 22
J 0
(-287 1708);
DISPLAY 0.680851 (-287 1708);
PAINT GREEN (-287 1708);
FORCEPROP 2 LAST CDS_LIB standard
J 0
(-225 1700);
DISPLAY INVISIBLE (-225 1700);
FORCEPROP 1 LAST BODY_TYPE PLUMBING
J 0
(-225 1750);
DISPLAY 0.872340 (-225 1750);
PAINT GREEN (-225 1750);
DISPLAY INVISIBLE (-225 1750);
FORCEPROP 1 LAST HDL_TAP TRUE
J 0
(100 1575);
DISPLAY 0.872340 (100 1575);
DISPLAY INVISIBLE (100 1575);
FORCEPROP 1 LAST PATH I73
J 0
(-227 1700);
DISPLAY 0.872340 (-227 1700);
PAINT GREEN (-227 1700);
DISPLAY INVISIBLE (-227 1700);
FORCEADD TAP..1
(-225 1650);
FORCEPROP 3 LASTPIN (-275 1650) SIG_NAME M_A_CPU1_SB_DQ<21>
J 0
(-265 1660);
DISPLAY 0.659574 (-265 1660);
PAINT MONO (-265 1660);
DISPLAY INVISIBLE (-265 1660);
FORCEPROP 1 LASTPIN (-275 1650) BN 21
J 0
(-287 1658);
DISPLAY 0.680851 (-287 1658);
PAINT GREEN (-287 1658);
FORCEPROP 2 LAST CDS_LIB standard
J 0
(-225 1650);
PAINT MONO (-225 1650);
DISPLAY INVISIBLE (-225 1650);
FORCEPROP 1 LAST BODY_TYPE PLUMBING
J 0
(-225 1700);
DISPLAY 0.872340 (-225 1700);
PAINT GREEN (-225 1700);
DISPLAY INVISIBLE (-225 1700);
FORCEPROP 1 LAST HDL_TAP TRUE
J 0
(100 1525);
DISPLAY 0.872340 (100 1525);
DISPLAY INVISIBLE (100 1525);
FORCEPROP 1 LAST PATH I74
J 0
(-227 1650);
DISPLAY 0.872340 (-227 1650);
PAINT GREEN (-227 1650);
DISPLAY INVISIBLE (-227 1650);
FORCEADD TAP..1
(-225 1750);
FORCEPROP 3 LASTPIN (-275 1750) SIG_NAME M_A_CPU1_SB_DQ<23>
J 0
(-265 1760);
DISPLAY 0.659574 (-265 1760);
PAINT MONO (-265 1760);
DISPLAY INVISIBLE (-265 1760);
FORCEPROP 1 LASTPIN (-275 1750) BN 23
J 0
(-287 1758);
DISPLAY 0.680851 (-287 1758);
PAINT GREEN (-287 1758);
FORCEPROP 2 LAST CDS_LIB standard
J 0
(-225 1750);
DISPLAY INVISIBLE (-225 1750);
FORCEPROP 1 LAST BODY_TYPE PLUMBING
J 0
(-225 1800);
DISPLAY 0.872340 (-225 1800);
PAINT GREEN (-225 1800);
DISPLAY INVISIBLE (-225 1800);
FORCEPROP 1 LAST HDL_TAP TRUE
J 0
(100 1625);
DISPLAY 0.872340 (100 1625);
DISPLAY INVISIBLE (100 1625);
FORCEPROP 1 LAST PATH I75
J 0
(-227 1750);
DISPLAY 0.872340 (-227 1750);
PAINT GREEN (-227 1750);
DISPLAY INVISIBLE (-227 1750);
FORCEADD TAP..1
(-225 1800);
FORCEPROP 3 LASTPIN (-275 1800) SIG_NAME M_A_CPU1_SB_DQ<24>
J 0
(-265 1810);
DISPLAY 0.659574 (-265 1810);
PAINT MONO (-265 1810);
DISPLAY INVISIBLE (-265 1810);
FORCEPROP 1 LASTPIN (-275 1800) BN 24
J 0
(-287 1808);
DISPLAY 0.680851 (-287 1808);
PAINT GREEN (-287 1808);
FORCEPROP 2 LAST CDS_LIB standard
J 0
(-225 1800);
DISPLAY INVISIBLE (-225 1800);
FORCEPROP 1 LAST BODY_TYPE PLUMBING
J 0
(-225 1850);
DISPLAY 0.872340 (-225 1850);
PAINT GREEN (-225 1850);
DISPLAY INVISIBLE (-225 1850);
FORCEPROP 1 LAST HDL_TAP TRUE
J 0
(100 1675);
DISPLAY 0.872340 (100 1675);
DISPLAY INVISIBLE (100 1675);
FORCEPROP 1 LAST PATH I76
J 0
(-227 1800);
DISPLAY 0.872340 (-227 1800);
PAINT GREEN (-227 1800);
DISPLAY INVISIBLE (-227 1800);
FORCEADD TAP..1
(-225 1850);
FORCEPROP 3 LASTPIN (-275 1850) SIG_NAME M_A_CPU1_SB_DQ<25>
J 0
(-265 1860);
DISPLAY 0.659574 (-265 1860);
PAINT MONO (-265 1860);
DISPLAY INVISIBLE (-265 1860);
FORCEPROP 1 LASTPIN (-275 1850) BN 25
J 0
(-287 1858);
DISPLAY 0.680851 (-287 1858);
PAINT GREEN (-287 1858);
FORCEPROP 2 LAST CDS_LIB standard
J 0
(-225 1850);
DISPLAY INVISIBLE (-225 1850);
FORCEPROP 1 LAST BODY_TYPE PLUMBING
J 0
(-225 1900);
DISPLAY 0.872340 (-225 1900);
PAINT GREEN (-225 1900);
DISPLAY INVISIBLE (-225 1900);
FORCEPROP 1 LAST HDL_TAP TRUE
J 0
(100 1725);
DISPLAY 0.872340 (100 1725);
DISPLAY INVISIBLE (100 1725);
FORCEPROP 1 LAST PATH I77
J 0
(-227 1850);
DISPLAY 0.872340 (-227 1850);
PAINT GREEN (-227 1850);
DISPLAY INVISIBLE (-227 1850);
FORCEADD TAP..1
(-225 1900);
FORCEPROP 3 LASTPIN (-275 1900) SIG_NAME M_A_CPU1_SB_DQ<26>
J 0
(-265 1910);
DISPLAY 0.659574 (-265 1910);
PAINT MONO (-265 1910);
DISPLAY INVISIBLE (-265 1910);
FORCEPROP 1 LASTPIN (-275 1900) BN 26
J 0
(-287 1908);
DISPLAY 0.680851 (-287 1908);
PAINT GREEN (-287 1908);
FORCEPROP 2 LAST CDS_LIB standard
J 0
(-225 1900);
DISPLAY INVISIBLE (-225 1900);
FORCEPROP 1 LAST BODY_TYPE PLUMBING
J 0
(-225 1950);
DISPLAY 0.872340 (-225 1950);
PAINT GREEN (-225 1950);
DISPLAY INVISIBLE (-225 1950);
FORCEPROP 1 LAST HDL_TAP TRUE
J 0
(100 1775);
DISPLAY 0.872340 (100 1775);
DISPLAY INVISIBLE (100 1775);
FORCEPROP 1 LAST PATH I78
J 0
(-227 1900);
DISPLAY 0.872340 (-227 1900);
PAINT GREEN (-227 1900);
DISPLAY INVISIBLE (-227 1900);
FORCEADD TAP..1
(-225 2000);
FORCEPROP 3 LASTPIN (-275 2000) SIG_NAME M_A_CPU1_SB_DQ<28>
J 0
(-265 2010);
DISPLAY 0.659574 (-265 2010);
PAINT MONO (-265 2010);
DISPLAY INVISIBLE (-265 2010);
FORCEPROP 1 LASTPIN (-275 2000) BN 28
J 0
(-287 2008);
DISPLAY 0.680851 (-287 2008);
PAINT GREEN (-287 2008);
FORCEPROP 2 LAST CDS_LIB standard
J 0
(-225 2000);
DISPLAY INVISIBLE (-225 2000);
FORCEPROP 1 LAST BODY_TYPE PLUMBING
J 0
(-225 2050);
DISPLAY 0.872340 (-225 2050);
PAINT GREEN (-225 2050);
DISPLAY INVISIBLE (-225 2050);
FORCEPROP 1 LAST HDL_TAP TRUE
J 0
(100 1875);
DISPLAY 0.872340 (100 1875);
DISPLAY INVISIBLE (100 1875);
FORCEPROP 1 LAST PATH I79
J 0
(-227 2000);
DISPLAY 0.872340 (-227 2000);
PAINT GREEN (-227 2000);
DISPLAY INVISIBLE (-227 2000);
FORCEADD OFFPAGE..1
(-2700 1250);
FORCEPROP 2 LAST $XR7 105 
J 0
(-3162 1286);
DISPLAY 0.638298 (-3162 1286);
PAINT MONO (-3162 1286);
FORCEPROP 2 LAST $XR6 104 
J 0
(-3042 1286);
DISPLAY 0.638298 (-3042 1286);
PAINT MONO (-3042 1286);
FORCEPROP 2 LAST $XR5 103 
J 0
(-3192 1214);
DISPLAY 0.638298 (-3192 1214);
PAINT MONO (-3192 1214);
FORCEPROP 2 LAST $XR4 102 
J 0
(-3072 1214);
DISPLAY 0.638298 (-3072 1214);
PAINT MONO (-3072 1214);
FORCEPROP 2 LAST $XR3 101 
J 0
(-2952 1214);
DISPLAY 0.638298 (-2952 1214);
PAINT MONO (-2952 1214);
FORCEPROP 2 LAST $XR2 100 
J 0
(-3162 1250);
DISPLAY 0.638298 (-3162 1250);
PAINT MONO (-3162 1250);
FORCEPROP 2 LAST $XR1 98 
J 0
(-3042 1250);
DISPLAY 0.638298 (-3042 1250);
PAINT MONO (-3042 1250);
FORCEPROP 2 LAST $XR0 230 
J 0
(-2952 1250);
DISPLAY 0.638298 (-2952 1250);
PAINT MONO (-2952 1250);
FORCEPROP 2 LAST CDS_LIB standard
J 0
(-2700 1250);
PAINT MONO (-2700 1250);
DISPLAY INVISIBLE (-2700 1250);
FORCEPROP 1 LAST OFFPAGE TRUE
J 0
(-2375 1125);
DISPLAY 0.872340 (-2375 1125);
DISPLAY INVISIBLE (-2375 1125);
FORCEPROP 1 LAST COMMENT_BODY TRUE
J 0
(-2575 1150);
DISPLAY 0.872340 (-2575 1150);
PAINT GREEN (-2575 1150);
DISPLAY INVISIBLE (-2575 1150);
FORCEPROP 2 LAST PATH I8
J 0
(-2650 1325);
DISPLAY 1.021277 (-2650 1325);
DISPLAY INVISIBLE (-2650 1325);
FORCEADD TAP..1
(-225 1950);
FORCEPROP 3 LASTPIN (-275 1950) SIG_NAME M_A_CPU1_SB_DQ<27>
J 0
(-265 1960);
DISPLAY 0.659574 (-265 1960);
PAINT MONO (-265 1960);
DISPLAY INVISIBLE (-265 1960);
FORCEPROP 1 LASTPIN (-275 1950) BN 27
J 0
(-287 1958);
DISPLAY 0.680851 (-287 1958);
PAINT GREEN (-287 1958);
FORCEPROP 2 LAST CDS_LIB standard
J 0
(-225 1950);
DISPLAY INVISIBLE (-225 1950);
FORCEPROP 1 LAST BODY_TYPE PLUMBING
J 0
(-225 2000);
DISPLAY 0.872340 (-225 2000);
PAINT GREEN (-225 2000);
DISPLAY INVISIBLE (-225 2000);
FORCEPROP 1 LAST HDL_TAP TRUE
J 0
(100 1825);
DISPLAY 0.872340 (100 1825);
DISPLAY INVISIBLE (100 1825);
FORCEPROP 1 LAST PATH I80
J 0
(-227 1950);
DISPLAY 0.872340 (-227 1950);
PAINT GREEN (-227 1950);
DISPLAY INVISIBLE (-227 1950);
FORCEADD TAP..1
(-225 2050);
FORCEPROP 3 LASTPIN (-275 2050) SIG_NAME M_A_CPU1_SB_DQ<29>
J 0
(-265 2060);
DISPLAY 0.659574 (-265 2060);
PAINT MONO (-265 2060);
DISPLAY INVISIBLE (-265 2060);
FORCEPROP 1 LASTPIN (-275 2050) BN 29
J 0
(-287 2058);
DISPLAY 0.680851 (-287 2058);
PAINT GREEN (-287 2058);
FORCEPROP 2 LAST CDS_LIB standard
J 0
(-225 2050);
DISPLAY INVISIBLE (-225 2050);
FORCEPROP 1 LAST BODY_TYPE PLUMBING
J 0
(-225 2100);
DISPLAY 0.872340 (-225 2100);
PAINT GREEN (-225 2100);
DISPLAY INVISIBLE (-225 2100);
FORCEPROP 1 LAST HDL_TAP TRUE
J 0
(100 1925);
DISPLAY 0.872340 (100 1925);
DISPLAY INVISIBLE (100 1925);
FORCEPROP 1 LAST PATH I81
J 0
(-227 2050);
DISPLAY 0.872340 (-227 2050);
PAINT GREEN (-227 2050);
DISPLAY INVISIBLE (-227 2050);
FORCEADD TAP..1
(-225 2150);
FORCEPROP 3 LASTPIN (-275 2150) SIG_NAME M_A_CPU1_SB_DQ<31>
J 0
(-265 2160);
DISPLAY 0.659574 (-265 2160);
PAINT MONO (-265 2160);
DISPLAY INVISIBLE (-265 2160);
FORCEPROP 1 LASTPIN (-275 2150) BN 31
J 0
(-287 2158);
DISPLAY 0.680851 (-287 2158);
PAINT GREEN (-287 2158);
FORCEPROP 2 LAST CDS_LIB standard
J 0
(-225 2150);
DISPLAY INVISIBLE (-225 2150);
FORCEPROP 1 LAST BODY_TYPE PLUMBING
J 0
(-225 2200);
DISPLAY 0.872340 (-225 2200);
PAINT GREEN (-225 2200);
DISPLAY INVISIBLE (-225 2200);
FORCEPROP 1 LAST HDL_TAP TRUE
J 0
(100 2025);
DISPLAY 0.872340 (100 2025);
DISPLAY INVISIBLE (100 2025);
FORCEPROP 1 LAST PATH I82
J 0
(-227 2150);
DISPLAY 0.872340 (-227 2150);
PAINT GREEN (-227 2150);
DISPLAY INVISIBLE (-227 2150);
FORCEADD TAP..1
(-225 2100);
FORCEPROP 3 LASTPIN (-275 2100) SIG_NAME M_A_CPU1_SB_DQ<30>
J 0
(-265 2110);
DISPLAY 0.659574 (-265 2110);
PAINT MONO (-265 2110);
DISPLAY INVISIBLE (-265 2110);
FORCEPROP 1 LASTPIN (-275 2100) BN 30
J 0
(-287 2108);
DISPLAY 0.680851 (-287 2108);
PAINT GREEN (-287 2108);
FORCEPROP 2 LAST CDS_LIB standard
J 0
(-225 2100);
DISPLAY INVISIBLE (-225 2100);
FORCEPROP 1 LAST BODY_TYPE PLUMBING
J 0
(-225 2150);
DISPLAY 0.872340 (-225 2150);
PAINT GREEN (-225 2150);
DISPLAY INVISIBLE (-225 2150);
FORCEPROP 1 LAST HDL_TAP TRUE
J 0
(100 1975);
DISPLAY 0.872340 (100 1975);
DISPLAY INVISIBLE (100 1975);
FORCEPROP 1 LAST PATH I83
J 0
(-227 2100);
DISPLAY 0.872340 (-227 2100);
PAINT GREEN (-227 2100);
DISPLAY INVISIBLE (-227 2100);
FORCEADD TAP..1
(-225 2250);
FORCEPROP 3 LASTPIN (-275 2250) SIG_NAME M_A_CPU1_SA_DQ<0>
J 0
(-265 2260);
DISPLAY 0.659574 (-265 2260);
PAINT MONO (-265 2260);
DISPLAY INVISIBLE (-265 2260);
FORCEPROP 1 LASTPIN (-275 2250) BN 0
J 0
(-287 2258);
DISPLAY 0.680851 (-287 2258);
PAINT GREEN (-287 2258);
FORCEPROP 2 LAST CDS_LIB standard
J 0
(-225 2250);
PAINT MONO (-225 2250);
DISPLAY INVISIBLE (-225 2250);
FORCEPROP 1 LAST BODY_TYPE PLUMBING
J 0
(-225 2300);
DISPLAY 0.872340 (-225 2300);
PAINT GREEN (-225 2300);
DISPLAY INVISIBLE (-225 2300);
FORCEPROP 1 LAST HDL_TAP TRUE
J 0
(100 2125);
DISPLAY 0.872340 (100 2125);
DISPLAY INVISIBLE (100 2125);
FORCEPROP 1 LAST PATH I84
J 0
(-227 2250);
DISPLAY 0.872340 (-227 2250);
PAINT GREEN (-227 2250);
DISPLAY INVISIBLE (-227 2250);
FORCEADD TAP..1
(-225 2350);
FORCEPROP 3 LASTPIN (-275 2350) SIG_NAME M_A_CPU1_SA_DQ<2>
J 0
(-265 2360);
DISPLAY 0.659574 (-265 2360);
PAINT MONO (-265 2360);
DISPLAY INVISIBLE (-265 2360);
FORCEPROP 1 LASTPIN (-275 2350) BN 2
J 0
(-287 2358);
DISPLAY 0.680851 (-287 2358);
PAINT GREEN (-287 2358);
FORCEPROP 2 LAST CDS_LIB standard
J 0
(-225 2350);
PAINT MONO (-225 2350);
DISPLAY INVISIBLE (-225 2350);
FORCEPROP 1 LAST BODY_TYPE PLUMBING
J 0
(-225 2400);
DISPLAY 0.872340 (-225 2400);
PAINT GREEN (-225 2400);
DISPLAY INVISIBLE (-225 2400);
FORCEPROP 1 LAST HDL_TAP TRUE
J 0
(100 2225);
DISPLAY 0.872340 (100 2225);
DISPLAY INVISIBLE (100 2225);
FORCEPROP 1 LAST PATH I85
J 0
(-227 2350);
DISPLAY 0.872340 (-227 2350);
PAINT GREEN (-227 2350);
DISPLAY INVISIBLE (-227 2350);
FORCEADD TAP..1
(-225 2300);
FORCEPROP 3 LASTPIN (-275 2300) SIG_NAME M_A_CPU1_SA_DQ<1>
J 0
(-265 2310);
DISPLAY 0.659574 (-265 2310);
PAINT MONO (-265 2310);
DISPLAY INVISIBLE (-265 2310);
FORCEPROP 1 LASTPIN (-275 2300) BN 1
J 0
(-287 2308);
DISPLAY 0.680851 (-287 2308);
PAINT GREEN (-287 2308);
FORCEPROP 2 LAST CDS_LIB standard
J 0
(-225 2300);
PAINT MONO (-225 2300);
DISPLAY INVISIBLE (-225 2300);
FORCEPROP 1 LAST BODY_TYPE PLUMBING
J 0
(-225 2350);
DISPLAY 0.872340 (-225 2350);
PAINT GREEN (-225 2350);
DISPLAY INVISIBLE (-225 2350);
FORCEPROP 1 LAST HDL_TAP TRUE
J 0
(100 2175);
DISPLAY 0.872340 (100 2175);
DISPLAY INVISIBLE (100 2175);
FORCEPROP 1 LAST PATH I86
J 0
(-227 2300);
DISPLAY 0.872340 (-227 2300);
PAINT GREEN (-227 2300);
DISPLAY INVISIBLE (-227 2300);
FORCEADD TAP..1
(-225 2400);
FORCEPROP 3 LASTPIN (-275 2400) SIG_NAME M_A_CPU1_SA_DQ<3>
J 0
(-265 2410);
DISPLAY 0.659574 (-265 2410);
PAINT MONO (-265 2410);
DISPLAY INVISIBLE (-265 2410);
FORCEPROP 1 LASTPIN (-275 2400) BN 3
J 0
(-287 2408);
DISPLAY 0.680851 (-287 2408);
PAINT GREEN (-287 2408);
FORCEPROP 2 LAST CDS_LIB standard
J 0
(-225 2400);
PAINT MONO (-225 2400);
DISPLAY INVISIBLE (-225 2400);
FORCEPROP 1 LAST BODY_TYPE PLUMBING
J 0
(-225 2450);
DISPLAY 0.872340 (-225 2450);
PAINT GREEN (-225 2450);
DISPLAY INVISIBLE (-225 2450);
FORCEPROP 1 LAST HDL_TAP TRUE
J 0
(100 2275);
DISPLAY 0.872340 (100 2275);
DISPLAY INVISIBLE (100 2275);
FORCEPROP 1 LAST PATH I87
J 0
(-227 2400);
DISPLAY 0.872340 (-227 2400);
PAINT GREEN (-227 2400);
DISPLAY INVISIBLE (-227 2400);
FORCEADD TAP..1
(-225 2500);
FORCEPROP 3 LASTPIN (-275 2500) SIG_NAME M_A_CPU1_SA_DQ<5>
J 0
(-265 2510);
DISPLAY 0.659574 (-265 2510);
PAINT MONO (-265 2510);
DISPLAY INVISIBLE (-265 2510);
FORCEPROP 1 LASTPIN (-275 2500) BN 5
J 0
(-287 2508);
DISPLAY 0.680851 (-287 2508);
PAINT GREEN (-287 2508);
FORCEPROP 2 LAST CDS_LIB standard
J 0
(-225 2500);
PAINT MONO (-225 2500);
DISPLAY INVISIBLE (-225 2500);
FORCEPROP 1 LAST BODY_TYPE PLUMBING
J 0
(-225 2550);
DISPLAY 0.872340 (-225 2550);
PAINT GREEN (-225 2550);
DISPLAY INVISIBLE (-225 2550);
FORCEPROP 1 LAST HDL_TAP TRUE
J 0
(100 2375);
DISPLAY 0.872340 (100 2375);
DISPLAY INVISIBLE (100 2375);
FORCEPROP 1 LAST PATH I88
J 0
(-227 2500);
DISPLAY 0.872340 (-227 2500);
PAINT GREEN (-227 2500);
DISPLAY INVISIBLE (-227 2500);
FORCEADD TAP..1
(-225 2450);
FORCEPROP 3 LASTPIN (-275 2450) SIG_NAME M_A_CPU1_SA_DQ<4>
J 0
(-265 2460);
DISPLAY 0.659574 (-265 2460);
PAINT MONO (-265 2460);
DISPLAY INVISIBLE (-265 2460);
FORCEPROP 1 LASTPIN (-275 2450) BN 4
J 0
(-287 2458);
DISPLAY 0.680851 (-287 2458);
PAINT GREEN (-287 2458);
FORCEPROP 2 LAST CDS_LIB standard
J 0
(-225 2450);
PAINT MONO (-225 2450);
DISPLAY INVISIBLE (-225 2450);
FORCEPROP 1 LAST BODY_TYPE PLUMBING
J 0
(-225 2500);
DISPLAY 0.872340 (-225 2500);
PAINT GREEN (-225 2500);
DISPLAY INVISIBLE (-225 2500);
FORCEPROP 1 LAST HDL_TAP TRUE
J 0
(100 2325);
DISPLAY 0.872340 (100 2325);
DISPLAY INVISIBLE (100 2325);
FORCEPROP 1 LAST PATH I89
J 0
(-227 2450);
DISPLAY 0.872340 (-227 2450);
PAINT GREEN (-227 2450);
DISPLAY INVISIBLE (-227 2450);
FORCEADD TAP..1
(-225 2600);
FORCEPROP 3 LASTPIN (-275 2600) SIG_NAME M_A_CPU1_SA_DQ<7>
J 0
(-265 2610);
DISPLAY 0.659574 (-265 2610);
PAINT MONO (-265 2610);
DISPLAY INVISIBLE (-265 2610);
FORCEPROP 1 LASTPIN (-275 2600) BN 7
J 0
(-287 2608);
DISPLAY 0.680851 (-287 2608);
PAINT GREEN (-287 2608);
FORCEPROP 2 LAST CDS_LIB standard
J 0
(-225 2600);
PAINT MONO (-225 2600);
DISPLAY INVISIBLE (-225 2600);
FORCEPROP 1 LAST BODY_TYPE PLUMBING
J 0
(-225 2650);
DISPLAY 0.872340 (-225 2650);
PAINT GREEN (-225 2650);
DISPLAY INVISIBLE (-225 2650);
FORCEPROP 1 LAST HDL_TAP TRUE
J 0
(100 2475);
DISPLAY 0.872340 (100 2475);
DISPLAY INVISIBLE (100 2475);
FORCEPROP 1 LAST PATH I90
J 0
(-227 2600);
DISPLAY 0.872340 (-227 2600);
PAINT GREEN (-227 2600);
DISPLAY INVISIBLE (-227 2600);
FORCEADD TAP..1
(-225 2550);
FORCEPROP 3 LASTPIN (-275 2550) SIG_NAME M_A_CPU1_SA_DQ<6>
J 0
(-265 2560);
DISPLAY 0.659574 (-265 2560);
PAINT MONO (-265 2560);
DISPLAY INVISIBLE (-265 2560);
FORCEPROP 1 LASTPIN (-275 2550) BN 6
J 0
(-287 2558);
DISPLAY 0.680851 (-287 2558);
PAINT GREEN (-287 2558);
FORCEPROP 2 LAST CDS_LIB standard
J 0
(-225 2550);
PAINT MONO (-225 2550);
DISPLAY INVISIBLE (-225 2550);
FORCEPROP 1 LAST BODY_TYPE PLUMBING
J 0
(-225 2600);
DISPLAY 0.872340 (-225 2600);
PAINT GREEN (-225 2600);
DISPLAY INVISIBLE (-225 2600);
FORCEPROP 1 LAST HDL_TAP TRUE
J 0
(100 2425);
DISPLAY 0.872340 (100 2425);
DISPLAY INVISIBLE (100 2425);
FORCEPROP 1 LAST PATH I91
J 0
(-227 2550);
DISPLAY 0.872340 (-227 2550);
PAINT GREEN (-227 2550);
DISPLAY INVISIBLE (-227 2550);
FORCEADD TAP..1
(-225 2650);
FORCEPROP 3 LASTPIN (-275 2650) SIG_NAME M_A_CPU1_SA_DQ<8>
J 0
(-265 2660);
DISPLAY 0.659574 (-265 2660);
PAINT MONO (-265 2660);
DISPLAY INVISIBLE (-265 2660);
FORCEPROP 1 LASTPIN (-275 2650) BN 8
J 0
(-287 2658);
DISPLAY 0.680851 (-287 2658);
PAINT GREEN (-287 2658);
FORCEPROP 2 LAST CDS_LIB standard
J 0
(-225 2650);
PAINT MONO (-225 2650);
DISPLAY INVISIBLE (-225 2650);
FORCEPROP 1 LAST BODY_TYPE PLUMBING
J 0
(-225 2700);
DISPLAY 0.872340 (-225 2700);
PAINT GREEN (-225 2700);
DISPLAY INVISIBLE (-225 2700);
FORCEPROP 1 LAST HDL_TAP TRUE
J 0
(100 2525);
DISPLAY 0.872340 (100 2525);
DISPLAY INVISIBLE (100 2525);
FORCEPROP 1 LAST PATH I92
J 0
(-227 2650);
DISPLAY 0.872340 (-227 2650);
PAINT GREEN (-227 2650);
DISPLAY INVISIBLE (-227 2650);
FORCEADD TAP..1
(-225 2700);
FORCEPROP 3 LASTPIN (-275 2700) SIG_NAME M_A_CPU1_SA_DQ<9>
J 0
(-265 2710);
DISPLAY 0.659574 (-265 2710);
PAINT MONO (-265 2710);
DISPLAY INVISIBLE (-265 2710);
FORCEPROP 1 LASTPIN (-275 2700) BN 9
J 0
(-287 2708);
DISPLAY 0.680851 (-287 2708);
PAINT GREEN (-287 2708);
FORCEPROP 2 LAST CDS_LIB standard
J 0
(-225 2700);
PAINT MONO (-225 2700);
DISPLAY INVISIBLE (-225 2700);
FORCEPROP 1 LAST BODY_TYPE PLUMBING
J 0
(-225 2750);
DISPLAY 0.872340 (-225 2750);
PAINT GREEN (-225 2750);
DISPLAY INVISIBLE (-225 2750);
FORCEPROP 1 LAST HDL_TAP TRUE
J 0
(100 2575);
DISPLAY 0.872340 (100 2575);
DISPLAY INVISIBLE (100 2575);
FORCEPROP 1 LAST PATH I93
J 0
(-227 2700);
DISPLAY 0.872340 (-227 2700);
PAINT GREEN (-227 2700);
DISPLAY INVISIBLE (-227 2700);
FORCEADD TAP..1
(-225 2750);
FORCEPROP 3 LASTPIN (-275 2750) SIG_NAME M_A_CPU1_SA_DQ<10>
J 0
(-265 2760);
DISPLAY 0.659574 (-265 2760);
PAINT MONO (-265 2760);
DISPLAY INVISIBLE (-265 2760);
FORCEPROP 1 LASTPIN (-275 2750) BN 10
J 0
(-287 2758);
DISPLAY 0.680851 (-287 2758);
PAINT GREEN (-287 2758);
FORCEPROP 2 LAST CDS_LIB standard
J 0
(-225 2750);
PAINT MONO (-225 2750);
DISPLAY INVISIBLE (-225 2750);
FORCEPROP 1 LAST BODY_TYPE PLUMBING
J 0
(-225 2800);
DISPLAY 0.872340 (-225 2800);
PAINT GREEN (-225 2800);
DISPLAY INVISIBLE (-225 2800);
FORCEPROP 1 LAST HDL_TAP TRUE
J 0
(100 2625);
DISPLAY 0.872340 (100 2625);
DISPLAY INVISIBLE (100 2625);
FORCEPROP 1 LAST PATH I94
J 0
(-227 2750);
DISPLAY 0.872340 (-227 2750);
PAINT GREEN (-227 2750);
DISPLAY INVISIBLE (-227 2750);
FORCEADD TAP..1
(-225 2800);
FORCEPROP 3 LASTPIN (-275 2800) SIG_NAME M_A_CPU1_SA_DQ<11>
J 0
(-265 2810);
DISPLAY 0.659574 (-265 2810);
PAINT MONO (-265 2810);
DISPLAY INVISIBLE (-265 2810);
FORCEPROP 1 LASTPIN (-275 2800) BN 11
J 0
(-287 2808);
DISPLAY 0.680851 (-287 2808);
PAINT GREEN (-287 2808);
FORCEPROP 2 LAST CDS_LIB standard
J 0
(-225 2800);
PAINT MONO (-225 2800);
DISPLAY INVISIBLE (-225 2800);
FORCEPROP 1 LAST BODY_TYPE PLUMBING
J 0
(-225 2850);
DISPLAY 0.872340 (-225 2850);
PAINT GREEN (-225 2850);
DISPLAY INVISIBLE (-225 2850);
FORCEPROP 1 LAST HDL_TAP TRUE
J 0
(100 2675);
DISPLAY 0.872340 (100 2675);
DISPLAY INVISIBLE (100 2675);
FORCEPROP 1 LAST PATH I95
J 0
(-227 2800);
DISPLAY 0.872340 (-227 2800);
PAINT GREEN (-227 2800);
DISPLAY INVISIBLE (-227 2800);
FORCEADD TAP..1
(-225 2900);
FORCEPROP 3 LASTPIN (-275 2900) SIG_NAME M_A_CPU1_SA_DQ<13>
J 0
(-265 2910);
DISPLAY 0.659574 (-265 2910);
PAINT MONO (-265 2910);
DISPLAY INVISIBLE (-265 2910);
FORCEPROP 1 LASTPIN (-275 2900) BN 13
J 0
(-287 2908);
DISPLAY 0.680851 (-287 2908);
PAINT GREEN (-287 2908);
FORCEPROP 2 LAST CDS_LIB standard
J 0
(-225 2900);
PAINT MONO (-225 2900);
DISPLAY INVISIBLE (-225 2900);
FORCEPROP 1 LAST BODY_TYPE PLUMBING
J 0
(-225 2950);
DISPLAY 0.872340 (-225 2950);
PAINT GREEN (-225 2950);
DISPLAY INVISIBLE (-225 2950);
FORCEPROP 1 LAST HDL_TAP TRUE
J 0
(100 2775);
DISPLAY 0.872340 (100 2775);
DISPLAY INVISIBLE (100 2775);
FORCEPROP 1 LAST PATH I96
J 0
(-227 2900);
DISPLAY 0.872340 (-227 2900);
PAINT GREEN (-227 2900);
DISPLAY INVISIBLE (-227 2900);
FORCEADD TAP..1
(-225 2850);
FORCEPROP 3 LASTPIN (-275 2850) SIG_NAME M_A_CPU1_SA_DQ<12>
J 0
(-265 2860);
DISPLAY 0.659574 (-265 2860);
PAINT MONO (-265 2860);
DISPLAY INVISIBLE (-265 2860);
FORCEPROP 1 LASTPIN (-275 2850) BN 12
J 0
(-287 2858);
DISPLAY 0.680851 (-287 2858);
PAINT GREEN (-287 2858);
FORCEPROP 2 LAST CDS_LIB standard
J 0
(-225 2850);
PAINT MONO (-225 2850);
DISPLAY INVISIBLE (-225 2850);
FORCEPROP 1 LAST BODY_TYPE PLUMBING
J 0
(-225 2900);
DISPLAY 0.872340 (-225 2900);
PAINT GREEN (-225 2900);
DISPLAY INVISIBLE (-225 2900);
FORCEPROP 1 LAST HDL_TAP TRUE
J 0
(100 2725);
DISPLAY 0.872340 (100 2725);
DISPLAY INVISIBLE (100 2725);
FORCEPROP 1 LAST PATH I97
J 0
(-227 2850);
DISPLAY 0.872340 (-227 2850);
PAINT GREEN (-227 2850);
DISPLAY INVISIBLE (-227 2850);
FORCEADD TAP..1
(-225 2950);
FORCEPROP 3 LASTPIN (-275 2950) SIG_NAME M_A_CPU1_SA_DQ<14>
J 0
(-265 2960);
DISPLAY 0.659574 (-265 2960);
PAINT MONO (-265 2960);
DISPLAY INVISIBLE (-265 2960);
FORCEPROP 1 LASTPIN (-275 2950) BN 14
J 0
(-287 2958);
DISPLAY 0.680851 (-287 2958);
PAINT GREEN (-287 2958);
FORCEPROP 2 LAST CDS_LIB standard
J 0
(-225 2950);
PAINT MONO (-225 2950);
DISPLAY INVISIBLE (-225 2950);
FORCEPROP 1 LAST BODY_TYPE PLUMBING
J 0
(-225 3000);
DISPLAY 0.872340 (-225 3000);
PAINT GREEN (-225 3000);
DISPLAY INVISIBLE (-225 3000);
FORCEPROP 1 LAST HDL_TAP TRUE
J 0
(100 2825);
DISPLAY 0.872340 (100 2825);
DISPLAY INVISIBLE (100 2825);
FORCEPROP 1 LAST PATH I98
J 0
(-227 2950);
DISPLAY 0.872340 (-227 2950);
PAINT GREEN (-227 2950);
DISPLAY INVISIBLE (-227 2950);
FORCEADD TAP..1
(-225 3000);
FORCEPROP 3 LASTPIN (-275 3000) SIG_NAME M_A_CPU1_SA_DQ<15>
J 0
(-265 3010);
DISPLAY 0.659574 (-265 3010);
PAINT MONO (-265 3010);
DISPLAY INVISIBLE (-265 3010);
FORCEPROP 1 LASTPIN (-275 3000) BN 15
J 0
(-287 3008);
DISPLAY 0.680851 (-287 3008);
PAINT GREEN (-287 3008);
FORCEPROP 2 LAST CDS_LIB standard
J 0
(-225 3000);
PAINT MONO (-225 3000);
DISPLAY INVISIBLE (-225 3000);
FORCEPROP 1 LAST BODY_TYPE PLUMBING
J 0
(-225 3050);
DISPLAY 0.872340 (-225 3050);
PAINT GREEN (-225 3050);
DISPLAY INVISIBLE (-225 3050);
FORCEPROP 1 LAST HDL_TAP TRUE
J 0
(100 2875);
DISPLAY 0.872340 (100 2875);
DISPLAY INVISIBLE (100 2875);
FORCEPROP 1 LAST PATH I99
J 0
(-227 3000);
DISPLAY 0.872340 (-227 3000);
PAINT GREEN (-227 3000);
DISPLAY INVISIBLE (-227 3000);
FORCEADD CAD_NOTE..1
(1625 -650);
FORCEPROP 0 LAST S1 PLACE THE BYPASS CAPS CLOSE TO DIMM
J 0
(1500 -775);
DISPLAY 1.021277 (1500 -775);
PAINT WHITE (1500 -775);
FORCEPROP 2 LAST CDS_LIB logical_power
J 0
(1625 -650);
PAINT MONO (1625 -650);
DISPLAY INVISIBLE (1625 -650);
FORCEPROP 1 LAST COMMENT_BODY TRUE
J 0
(1650 -550);
DISPLAY 0.978723 (1650 -550);
DISPLAY INVISIBLE (1650 -550);
FORCEADD QUANTA_TITLE_BLOCK_C..1
(6100 -1950);
FORCEPROP 0 LAST CDS_CON_LAST_MODIFIED Fri Aug 25 14:01:19 2023
J 0
(4215 -1935);
PAINT MONO (4215 -1935);
DISPLAY INVISIBLE (4215 -1935);
FORCEPROP 1 LAST CUSTOM_TXT_CDS <CON_LAST_MODIFIED>
J 0
(4215 -1935);
DISPLAY 0.978723 (4215 -1935);
FORCEPROP 2 LAST CUSTOM_TXT_CDS <XR_PAGE_TITLE>
J 0
(-1790 3300);
DISPLAY 0.638298 (-1790 3300);
PAINT PINK (-1790 3300);
DISPLAY INVISIBLE (-1790 3300);
FORCEPROP 2 LAST CUSTOM_TXT_CDS <Q_NUMBER>
J 0
(4697 -1847);
DISPLAY 1.212766 (4697 -1847);
FORCEPROP 1 LAST CUSTOM_TXT_CDS <NAME_2>
J 0
(2925 -1900);
FORCEPROP 1 LAST CUSTOM_TXT_CDS <NAME_1>
J 0
(2925 -1775);
FORCEPROP 1 LAST CUSTOM_TXT_CDS <Q_PROJ>
J 0
(3718 -1848);
DISPLAY 1.212766 (3718 -1848);
FORCEPROP 1 LAST CUSTOM_TXT_CDS <Q_REV>
J 0
(5916 -1847);
DISPLAY 1.212766 (5916 -1847);
FORCEPROP 1 LAST CUSTOM_TXT_CDS <CON_PAGE_NUM> OF <CON_TOTAL_PAGES>
J 0
(5654 -1932);
DISPLAY 0.978723 (5654 -1932);
FORCEPROP 1 LAST Q_TITLE DDR5 - CPU1 CHA DIMM2(BLACK)
J 0
(-3266 -1924);
DISPLAY 2.446809 (-3266 -1924);
PAINT GREEN (-3266 -1924);
FORCEPROP 1 LAST Q_DEPT 
J 1
(2337 -1901);
DISPLAY 1.957447 (2337 -1901);
PAINT GREEN (2337 -1901);
FORCEPROP 2 LAST CDS_XR_PAGE_TITLE CR-99 : @S9S_MB_2U_LIB.S9S_MB_2U(SCH_1):PAGE99
J 0
(-1790 3300);
DISPLAY 0.638298 (-1790 3300);
PAINT PINK (-1790 3300);
DISPLAY INVISIBLE (-1790 3300);
FORCEPROP 1 LAST COMMENT_BODY TRUE
J 0
(6112 -1963);
DISPLAY 0.978723 (6112 -1963);
PAINT GREEN (6112 -1963);
DISPLAY INVISIBLE (6112 -1963);
FORCEPROP 2 LAST PAGE_BORDER TRUE
J 0
(-1790 3300);
DISPLAY 0.638298 (-1790 3300);
PAINT PINK (-1790 3300);
DISPLAY INVISIBLE (-1790 3300);
FORCEPROP 1 LAST CDS_LMAN_SYM_OUTLINE -9475,6775,100,-125
J 0
(6100 -1950);
DISPLAY 0.468085 (6100 -1950);
PAINT GREEN (6100 -1950);
DISPLAY INVISIBLE (6100 -1950);
FORCEPROP 2 LAST CDS_LIB pure_quanta
J 0
(6100 -1950);
PAINT MONO (6100 -1950);
DISPLAY INVISIBLE (6100 -1950);
WIRE 17 -1 (-175 3825)(550 3825);
FORCEPROP 2 LAST SIG_NAME M_A_CPU1_SA_DQ<31:0>
J 0
(-110 3835);
DISPLAY 0.680851 (-110 3835);
PAINT WHITE (-110 3835);
WIRE 17 -1 (-2750 2425)(-1925 2425);
FORCEPROP 2 LAST SIG_NAME M_A_CPU1_SA_CB<7:0>
J 0
(-2660 2435);
DISPLAY 0.680851 (-2660 2435);
PAINT WHITE (-2660 2435);
WIRE 17 -1 (-1925 2275)(-1925 2325);
WIRE 17 -1 (-1925 2225)(-1925 2275);
WIRE 17 -1 (-1925 2325)(-1925 2375);
WIRE 17 -1 (-1925 2375)(-1925 2425);
WIRE 17 -1 (-1925 2175)(-1925 2225);
WIRE 17 -1 (-1925 2125)(-1925 2175);
WIRE 17 -1 (-1925 2075)(-1925 2125);
WIRE 17 -1 (-2750 1975)(-1925 1975);
FORCEPROP 2 LAST SIG_NAME M_A_CPU1_SB_CB<7:0>
J 0
(-2660 1985);
DISPLAY 0.680851 (-2660 1985);
PAINT WHITE (-2660 1985);
WIRE 17 -1 (-1925 3525)(-1925 3575);
WIRE 17 -1 (-1925 3575)(-1925 3625);
WIRE 17 -1 (-1925 3625)(-1925 3675);
WIRE 17 -1 (-1925 3675)(-1925 3725);
WIRE 17 -1 (-1925 3725)(-1925 3775);
WIRE 17 -1 (-1925 3775)(-1925 3825);
WIRE 17 -1 (-2750 3825)(-1925 3825);
FORCEPROP 2 LAST SIG_NAME M_A_CPU1_SA_CA<6:0>
J 0
(-2660 3835);
DISPLAY 0.680851 (-2660 3835);
PAINT WHITE (-2660 3835);
WIRE 17 -1 (-1925 3125)(-1925 3175);
WIRE 17 -1 (-1925 3175)(-1925 3225);
WIRE 17 -1 (-1925 3225)(-1925 3275);
WIRE 17 -1 (-1925 3275)(-1925 3325);
WIRE 17 -1 (-1925 3325)(-1925 3375);
WIRE 17 -1 (-1925 3375)(-1925 3425);
WIRE 17 -1 (-2750 3425)(-1925 3425);
FORCEPROP 2 LAST SIG_NAME M_A_CPU1_SB_CA<6:0>
J 0
(-2660 3435);
DISPLAY 0.680851 (-2660 3435);
PAINT WHITE (-2660 3435);
WIRE 17 -1 (-1925 1925)(-1925 1975);
WIRE 17 -1 (-1925 1875)(-1925 1925);
WIRE 17 -1 (-1925 1825)(-1925 1875);
WIRE 17 -1 (-1925 1775)(-1925 1825);
WIRE 17 -1 (-1925 1725)(-1925 1775);
WIRE 17 -1 (-1925 1675)(-1925 1725);
WIRE 17 -1 (-1925 1625)(-1925 1675);
WIRE 17 -1 (-175 3775)(-175 3825);
WIRE 17 -1 (-175 3725)(-175 3775);
WIRE 17 -1 (-175 3675)(-175 3725);
WIRE 17 -1 (-175 3625)(-175 3675);
WIRE 17 -1 (-175 3575)(-175 3625);
WIRE 17 -1 (-175 3525)(-175 3575);
WIRE 17 -1 (-175 3475)(-175 3525);
WIRE 17 -1 (-175 3425)(-175 3475);
WIRE 17 -1 (-175 3375)(-175 3425);
WIRE 17 -1 (-175 3325)(-175 3375);
WIRE 17 -1 (-175 3275)(-175 3325);
WIRE 17 -1 (-175 3225)(-175 3275);
WIRE 17 -1 (-175 3175)(-175 3225);
WIRE 17 -1 (-175 3125)(-175 3175);
WIRE 17 -1 (-175 3075)(-175 3125);
WIRE 17 -1 (-175 3025)(-175 3075);
WIRE 17 -1 (-175 2975)(-175 3025);
WIRE 17 -1 (-175 2925)(-175 2975);
WIRE 17 -1 (-175 2875)(-175 2925);
WIRE 17 -1 (-175 2825)(-175 2875);
WIRE 17 -1 (-175 2775)(-175 2825);
WIRE 17 -1 (-175 2725)(-175 2775);
WIRE 17 -1 (-175 2675)(-175 2725);
WIRE 17 -1 (-175 2625)(-175 2675);
WIRE 17 -1 (-175 2575)(-175 2625);
WIRE 17 -1 (-175 2525)(-175 2575);
WIRE 17 -1 (-175 2475)(-175 2525);
WIRE 17 -1 (-175 2425)(-175 2475);
WIRE 17 -1 (-175 2375)(-175 2425);
WIRE 17 -1 (-175 2325)(-175 2375);
WIRE 17 -1 (-175 2275)(-175 2325);
WIRE 17 -1 (-175 2175)(550 2175);
FORCEPROP 2 LAST SIG_NAME M_A_CPU1_SB_DQ<31:0>
J 0
(-110 2185);
DISPLAY 0.680851 (-110 2185);
PAINT WHITE (-110 2185);
WIRE 17 -1 (-175 2125)(-175 2175);
WIRE 17 -1 (-175 2075)(-175 2125);
WIRE 17 -1 (-175 2025)(-175 2075);
WIRE 17 -1 (-175 1975)(-175 2025);
WIRE 17 -1 (-175 1925)(-175 1975);
WIRE 17 -1 (-175 1875)(-175 1925);
WIRE 17 -1 (-175 1825)(-175 1875);
WIRE 17 -1 (-175 1775)(-175 1825);
WIRE 17 -1 (-175 1725)(-175 1775);
WIRE 17 -1 (-175 1675)(-175 1725);
WIRE 17 -1 (-175 1625)(-175 1675);
WIRE 17 -1 (-175 1575)(-175 1625);
WIRE 17 -1 (-175 1525)(-175 1575);
WIRE 17 -1 (-175 1475)(-175 1525);
WIRE 17 -1 (-175 1425)(-175 1475);
WIRE 17 -1 (-175 1375)(-175 1425);
WIRE 17 -1 (-175 1325)(-175 1375);
WIRE 17 -1 (-175 1275)(-175 1325);
WIRE 17 -1 (-175 1225)(-175 1275);
WIRE 17 -1 (-175 1175)(-175 1225);
WIRE 17 -1 (-175 1125)(-175 1175);
WIRE 17 -1 (-175 1075)(-175 1125);
WIRE 17 -1 (-175 1025)(-175 1075);
WIRE 17 -1 (-175 975)(-175 1025);
WIRE 17 -1 (-175 925)(-175 975);
WIRE 17 -1 (-175 875)(-175 925);
WIRE 17 -1 (-175 825)(-175 875);
WIRE 17 -1 (-175 775)(-175 825);
WIRE 17 -1 (-175 725)(-175 775);
WIRE 17 -1 (-175 675)(-175 725);
WIRE 17 -1 (-175 625)(-175 675);
WIRE 17 -1 (2575 1875)(2575 1975);
WIRE 17 -1 (2575 1975)(2575 2075);
WIRE 17 -1 (2575 2075)(2575 2175);
WIRE 17 -1 (2575 2275)(2575 2175);
WIRE 17 -1 (2575 2275)(2575 2375);
WIRE 17 -1 (2575 2375)(2575 2475);
WIRE 17 -1 (2575 2475)(2575 2575);
WIRE 17 -1 (2575 2575)(2575 2675);
WIRE 17 -1 (2575 2675)(2575 2775);
WIRE 17 -1 (2575 2775)(3600 2775);
FORCEPROP 2 LAST SIG_NAME M_A_CPU1_SB_DQS_DP<9:0>
J 0
(2815 2785);
DISPLAY 0.680851 (2815 2785);
PAINT WHITE (2815 2785);
WIRE 17 -1 (2575 2925)(2575 3025);
WIRE 17 -1 (2575 3025)(2575 3125);
WIRE 17 -1 (2575 3125)(2575 3225);
WIRE 17 -1 (2575 3325)(2575 3225);
WIRE 17 -1 (2575 3325)(2575 3425);
WIRE 17 -1 (2575 3425)(2575 3525);
WIRE 17 -1 (2575 3525)(2575 3625);
WIRE 17 -1 (2575 3625)(2575 3725);
WIRE 17 -1 (2575 3725)(2575 3825);
WIRE 17 -1 (2575 3825)(3600 3825);
FORCEPROP 2 LAST SIG_NAME M_A_CPU1_SA_DQS_DP<9:0>
J 0
(2815 3835);
DISPLAY 0.680851 (2815 3835);
PAINT WHITE (2815 3835);
WIRE 17 -1 (2750 1925)(2750 2025);
WIRE 17 -1 (2750 1825)(2750 1925);
WIRE 17 -1 (2750 2025)(2750 2125);
WIRE 17 -1 (2750 2225)(2750 2125);
WIRE 17 -1 (2750 2225)(2750 2325);
WIRE 17 -1 (2750 2325)(2750 2425);
WIRE 17 -1 (2750 2425)(2750 2525);
WIRE 17 -1 (2750 2525)(2750 2625);
WIRE 17 -1 (2750 2625)(2750 2725);
WIRE 17 -1 (2750 2725)(3600 2725);
FORCEPROP 2 LAST SIG_NAME M_A_CPU1_SB_DQS_DN<9:0>
J 0
(2815 2735);
DISPLAY 0.680851 (2815 2735);
PAINT WHITE (2815 2735);
WIRE 17 -1 (2750 2875)(2750 2975);
WIRE 17 -1 (2750 2975)(2750 3075);
WIRE 17 -1 (2750 3075)(2750 3175);
WIRE 17 -1 (2750 3275)(2750 3175);
WIRE 17 -1 (2750 3275)(2750 3375);
WIRE 17 -1 (2750 3375)(2750 3475);
WIRE 17 -1 (2750 3475)(2750 3575);
WIRE 17 -1 (2750 3575)(2750 3675);
WIRE 17 -1 (2750 3675)(2750 3775);
WIRE 17 -1 (2750 3775)(3600 3775);
FORCEPROP 2 LAST SIG_NAME M_A_CPU1_SA_DQS_DN<9:0>
J 0
(2815 3785);
DISPLAY 0.680851 (2815 3785);
PAINT WHITE (2815 3785);
WIRE 16 -1 (-2700 1625)(-2700 1350);
WIRE 16 -1 (4200 4300)(4200 3800);
WIRE 16 -1 (2500 200)(2500 150);
WIRE 16 -1 (1500 25)(1500 200);
WIRE 16 -1 (5900 450)(5900 150);
WIRE 16 -1 (5900 500)(5900 450);
WIRE 16 -1 (5650 450)(5900 450);
WIRE 16 -1 (4200 150)(4200 550);
WIRE 16 -1 (3125 -400)(3125 -325);
WIRE 16 -1 (1500 -175)(1500 -400);
WIRE 16 -1 (-1650 -525)(-1650 -450);
WIRE 16 3135 (1150 425)(1150 -875);
WIRE 16 3135 (3750 425)(1150 425);
WIRE 16 3135 (1150 -875)(3750 -875);
WIRE 16 3135 (3750 -875)(3750 425);
WIRE 16 -1 (2500 -325)(2500 -175);
WIRE 16 -1 (3125 -325)(2500 -325);
WIRE 16 -1 (3125 -325)(3125 -175);
WIRE 16 -1 (-2700 1350)(-1650 1350);
WIRE 16 -1 (-1650 1300)(-2650 1300);
FORCEPROP 2 LAST SIG_NAME PD_CHA_CPU1_DIMM2_SAA
J 0
(-2660 1310);
DISPLAY 0.680851 (-2660 1310);
PAINT WHITE (-2660 1310);
WIRE 16 -1 (-1650 1250)(-2650 1250);
FORCEPROP 2 LAST SIG_NAME I3C_SPD_DDRABCD_CPU1_LVC1_SDA
J 0
(-2660 1260);
DISPLAY 0.680851 (-2660 1260);
PAINT WHITE (-2660 1260);
WIRE 16 -1 (-3150 1075)(-2950 1075);
WIRE 16 -1 (-3150 1075)(-3150 1200);
WIRE 16 -1 (-1650 1200)(-3150 1200);
FORCEPROP 2 LAST SIG_NAME I3C_SPD_DDRABCD_CPU1_LVC1_SCL_R2
J 0
(-2710 1210);
DISPLAY 0.680851 (-2710 1210);
PAINT WHITE (-2710 1210);
WIRE 16 -1 (-1650 1450)(-2750 1450);
FORCEPROP 2 LAST SIG_NAME M_A_CPU1_ALERT_N
J 0
(-2662 1459);
DISPLAY 0.680851 (-2662 1459);
PAINT WHITE (-2662 1459);
WIRE 16 -1 (-2025 1500)(-1650 1500);
WIRE 16 -1 (-2025 1550)(-2750 1550);
FORCEPROP 2 LAST SIG_NAME RST_M_AB_CPU1_FPGA_N
J 0
(-2662 1559);
DISPLAY 0.680851 (-2662 1559);
PAINT WHITE (-2662 1559);
WIRE 16 -1 (-2025 1550)(-2025 1500);
WIRE 16 -1 (-1525 1025)(-1550 1025);
WIRE 16 -1 (-2750 1075)(-1525 1075);
FORCEPROP 2 LAST SIG_NAME I3C_SPD_DDRABCD_CPU1_LVC1_SCL
J 0
(-2560 1085);
DISPLAY 0.680851 (-2560 1085);
PAINT WHITE (-2560 1085);
WIRE 16 -1 (-1525 1075)(-1525 1025);
WIRE 16 -1 (2375 2300)(2650 2300);
WIRE 16 -1 (2375 3750)(2650 3750);
WIRE 16 -1 (2375 3650)(2650 3650);
WIRE 16 -1 (2375 3550)(2650 3550);
WIRE 16 -1 (2375 3350)(2650 3350);
WIRE 16 -1 (2375 3450)(2650 3450);
WIRE 16 -1 (2375 3250)(2650 3250);
WIRE 16 -1 (2375 3150)(2650 3150);
WIRE 16 -1 (2375 3050)(2650 3050);
WIRE 16 -1 (2375 2950)(2650 2950);
WIRE 16 -1 (2375 2850)(2650 2850);
WIRE 16 -1 (2375 2700)(2650 2700);
WIRE 16 -1 (2375 2600)(2650 2600);
WIRE 16 -1 (2375 2500)(2650 2500);
WIRE 16 -1 (2375 2400)(2650 2400);
WIRE 16 -1 (2375 2200)(2650 2200);
WIRE 16 -1 (2375 2100)(2650 2100);
WIRE 16 -1 (2375 2000)(2650 2000);
WIRE 16 -1 (2375 1800)(2650 1800);
WIRE 16 -1 (2375 1900)(2650 1900);
WIRE 16 -1 (2375 3800)(2475 3800);
WIRE 16 -1 (2375 3700)(2475 3700);
WIRE 16 -1 (2375 3600)(2475 3600);
WIRE 16 -1 (2375 3500)(2475 3500);
WIRE 16 -1 (2375 3400)(2475 3400);
WIRE 16 -1 (2375 3300)(2475 3300);
WIRE 16 -1 (2375 3200)(2475 3200);
WIRE 16 -1 (2375 3100)(2475 3100);
WIRE 16 -1 (2375 3000)(2475 3000);
WIRE 16 -1 (2375 2900)(2475 2900);
WIRE 16 -1 (2375 2750)(2475 2750);
WIRE 16 -1 (2375 2650)(2475 2650);
WIRE 16 -1 (2375 2550)(2475 2550);
WIRE 16 -1 (2375 2450)(2475 2450);
WIRE 16 -1 (2375 2350)(2475 2350);
WIRE 16 -1 (2375 2250)(2475 2250);
WIRE 16 -1 (2375 2050)(2475 2050);
WIRE 16 -1 (2375 2150)(2475 2150);
WIRE 16 -1 (2375 1950)(2475 1950);
WIRE 16 -1 (2375 1850)(2475 1850);
WIRE 16 -1 (-450 1950)(-275 1950);
WIRE 16 -1 (-1825 1650)(-1650 1650);
WIRE 16 -1 (4450 3700)(4200 3700);
WIRE 16 -1 (4200 3750)(4200 3700);
WIRE 16 -1 (4200 3750)(4450 3750);
WIRE 16 -1 (4200 3800)(4200 3750);
WIRE 16 -1 (4450 3800)(4200 3800);
WIRE 16 -1 (-1650 3000)(-2750 3000);
FORCEPROP 2 LAST SIG_NAME M_A_CPU1_SA_PAR
J 0
(-2662 3009);
DISPLAY 0.680851 (-2662 3009);
PAINT WHITE (-2662 3009);
WIRE 16 -1 (-1650 2950)(-2750 2950);
FORCEPROP 2 LAST SIG_NAME M_A_CPU1_SB_PAR
J 0
(-2662 2959);
DISPLAY 0.680851 (-2662 2959);
PAINT WHITE (-2662 2959);
WIRE 16 -1 (-450 2450)(-275 2450);
WIRE 16 -1 (4200 550)(4450 550);
WIRE 16 -1 (4200 550)(4200 600);
WIRE 16 -1 (4200 600)(4450 600);
WIRE 16 -1 (4200 600)(4200 650);
WIRE 16 -1 (4200 650)(4450 650);
WIRE 16 -1 (4200 650)(4200 700);
WIRE 16 -1 (4200 700)(4450 700);
WIRE 16 -1 (4200 700)(4200 750);
WIRE 16 -1 (4200 750)(4450 750);
WIRE 16 -1 (4200 750)(4200 800);
WIRE 16 -1 (4200 800)(4450 800);
WIRE 16 -1 (4200 800)(4200 850);
WIRE 16 -1 (4200 850)(4450 850);
WIRE 16 -1 (4200 850)(4200 900);
WIRE 16 -1 (4200 900)(4450 900);
WIRE 16 -1 (4200 900)(4200 950);
WIRE 16 -1 (4200 950)(4450 950);
WIRE 16 -1 (4200 950)(4200 1000);
WIRE 16 -1 (4200 1000)(4450 1000);
WIRE 16 -1 (4200 1000)(4200 1050);
WIRE 16 -1 (4450 1050)(4200 1050);
WIRE 16 -1 (4200 1050)(4200 1100);
WIRE 16 -1 (4200 1100)(4450 1100);
WIRE 16 -1 (4200 1100)(4200 1150);
WIRE 16 -1 (4200 1150)(4450 1150);
WIRE 16 -1 (4200 1150)(4200 1200);
WIRE 16 -1 (4200 1200)(4450 1200);
WIRE 16 -1 (4200 1200)(4200 1250);
WIRE 16 -1 (4200 1250)(4450 1250);
WIRE 16 -1 (4200 1250)(4200 1300);
WIRE 16 -1 (4200 1300)(4450 1300);
WIRE 16 -1 (4200 1300)(4200 1350);
WIRE 16 -1 (4200 1350)(4450 1350);
WIRE 16 -1 (4200 1350)(4200 1400);
WIRE 16 -1 (4200 1400)(4450 1400);
WIRE 16 -1 (4200 1400)(4200 1450);
WIRE 16 -1 (4200 1450)(4450 1450);
WIRE 16 -1 (4200 1450)(4200 1500);
WIRE 16 -1 (4200 1500)(4450 1500);
WIRE 16 -1 (4200 1500)(4200 1550);
WIRE 16 -1 (4450 1550)(4200 1550);
WIRE 16 -1 (4200 1550)(4200 1600);
WIRE 16 -1 (4200 1600)(4450 1600);
WIRE 16 -1 (4200 1600)(4200 1650);
WIRE 16 -1 (4200 1650)(4450 1650);
WIRE 16 -1 (4200 1650)(4200 1700);
WIRE 16 -1 (4200 1700)(4450 1700);
WIRE 16 -1 (4200 1700)(4200 1750);
WIRE 16 -1 (4200 1750)(4450 1750);
WIRE 16 -1 (4200 1750)(4200 1800);
WIRE 16 -1 (4200 1800)(4450 1800);
WIRE 16 -1 (4200 1800)(4200 1850);
WIRE 16 -1 (4200 1850)(4450 1850);
WIRE 16 -1 (4200 1850)(4200 1900);
WIRE 16 -1 (4200 1900)(4450 1900);
WIRE 16 -1 (4200 1900)(4200 1950);
WIRE 16 -1 (4200 1950)(4450 1950);
WIRE 16 -1 (4200 1950)(4200 2000);
WIRE 16 -1 (4200 2000)(4450 2000);
WIRE 16 -1 (4200 2000)(4200 2050);
WIRE 16 -1 (4450 2050)(4200 2050);
WIRE 16 -1 (4200 2050)(4200 2100);
WIRE 16 -1 (4200 2100)(4450 2100);
WIRE 16 -1 (4200 2100)(4200 2150);
WIRE 16 -1 (4200 2150)(4450 2150);
WIRE 16 -1 (4200 2150)(4200 2200);
WIRE 16 -1 (4200 2200)(4450 2200);
WIRE 16 -1 (4200 2200)(4200 2250);
WIRE 16 -1 (4200 2250)(4450 2250);
WIRE 16 -1 (4200 2250)(4200 2300);
WIRE 16 -1 (4200 2300)(4450 2300);
WIRE 16 -1 (4200 2300)(4200 2350);
WIRE 16 -1 (4200 2350)(4450 2350);
WIRE 16 -1 (4200 2350)(4200 2400);
WIRE 16 -1 (4200 2400)(4450 2400);
WIRE 16 -1 (4200 2400)(4200 2450);
WIRE 16 -1 (4200 2450)(4450 2450);
WIRE 16 -1 (4200 2450)(4200 2500);
WIRE 16 -1 (4200 2500)(4450 2500);
WIRE 16 -1 (4200 2500)(4200 2550);
WIRE 16 -1 (4450 2550)(4200 2550);
WIRE 16 -1 (4200 2550)(4200 2600);
WIRE 16 -1 (4200 2600)(4450 2600);
WIRE 16 -1 (4200 2600)(4200 2650);
WIRE 16 -1 (4200 2650)(4450 2650);
WIRE 16 -1 (4200 2650)(4200 2700);
WIRE 16 -1 (4200 2700)(4450 2700);
WIRE 16 -1 (4200 2700)(4200 2750);
WIRE 16 -1 (4200 2750)(4450 2750);
WIRE 16 -1 (4200 2750)(4200 2800);
WIRE 16 -1 (4200 2800)(4450 2800);
WIRE 16 -1 (4200 2800)(4200 2850);
WIRE 16 -1 (4200 2850)(4450 2850);
WIRE 16 -1 (4200 2850)(4200 2900);
WIRE 16 -1 (4200 2900)(4450 2900);
WIRE 16 -1 (4200 2900)(4200 2950);
WIRE 16 -1 (4200 2950)(4450 2950);
WIRE 16 -1 (4200 2950)(4200 3000);
WIRE 16 -1 (4200 3000)(4450 3000);
WIRE 16 -1 (4200 3000)(4200 3050);
WIRE 16 -1 (4450 3050)(4200 3050);
WIRE 16 -1 (4200 3050)(4200 3100);
WIRE 16 -1 (4200 3100)(4450 3100);
WIRE 16 -1 (4200 3100)(4200 3150);
WIRE 16 -1 (4200 3150)(4450 3150);
WIRE 16 -1 (4200 3150)(4200 3200);
WIRE 16 -1 (4200 3200)(4450 3200);
WIRE 16 -1 (4200 3200)(4200 3250);
WIRE 16 -1 (4200 3250)(4450 3250);
WIRE 16 -1 (4200 3250)(4200 3300);
WIRE 16 -1 (4200 3300)(4450 3300);
WIRE 16 -1 (4200 3300)(4200 3350);
WIRE 16 -1 (4200 3350)(4450 3350);
WIRE 16 -1 (4200 3350)(4200 3400);
WIRE 16 -1 (4200 3400)(4450 3400);
WIRE 16 -1 (4200 3400)(4200 3450);
WIRE 16 -1 (4200 3450)(4450 3450);
WIRE 16 -1 (4200 3450)(4200 3500);
WIRE 16 -1 (4200 3500)(4450 3500);
WIRE 16 -1 (4200 3500)(4200 3550);
WIRE 16 -1 (4450 3550)(4200 3550);
WIRE 16 -1 (4200 3550)(4200 3600);
WIRE 16 -1 (4200 3600)(4450 3600);
WIRE 16 -1 (4200 3600)(4200 3650);
WIRE 16 -1 (4450 3650)(4200 3650);
WIRE 16 -1 (5650 500)(5900 500);
WIRE 16 -1 (5900 550)(5900 500);
WIRE 16 -1 (5650 550)(5900 550);
WIRE 16 -1 (5650 650)(5900 650);
WIRE 16 -1 (5900 650)(5900 550);
WIRE 16 -1 (5650 700)(5900 700);
WIRE 16 -1 (5900 700)(5900 650);
WIRE 16 -1 (5650 750)(5900 750);
WIRE 16 -1 (5900 700)(5900 750);
WIRE 16 -1 (5650 800)(5900 800);
WIRE 16 -1 (5900 800)(5900 750);
WIRE 16 -1 (5650 850)(5900 850);
WIRE 16 -1 (5900 850)(5900 800);
WIRE 16 -1 (5650 900)(5900 900);
WIRE 16 -1 (5900 900)(5900 850);
WIRE 16 -1 (5650 950)(5900 950);
WIRE 16 -1 (5900 950)(5900 900);
WIRE 16 -1 (5650 1000)(5900 1000);
WIRE 16 -1 (5900 1000)(5900 950);
WIRE 16 -1 (5900 1050)(5900 1000);
WIRE 16 -1 (5650 1050)(5900 1050);
WIRE 16 -1 (5900 1100)(5650 1100);
WIRE 16 -1 (5900 1100)(5900 1050);
WIRE 16 -1 (5900 1150)(5650 1150);
WIRE 16 -1 (5900 1150)(5900 1100);
WIRE 16 -1 (5900 1200)(5650 1200);
WIRE 16 -1 (5900 1200)(5900 1150);
WIRE 16 -1 (5650 1250)(5900 1250);
WIRE 16 -1 (5900 1200)(5900 1250);
WIRE 16 -1 (5900 1300)(5650 1300);
WIRE 16 -1 (5900 1250)(5900 1300);
WIRE 16 -1 (5900 1350)(5650 1350);
WIRE 16 -1 (5900 1350)(5900 1300);
WIRE 16 -1 (5900 1400)(5650 1400);
WIRE 16 -1 (5900 1400)(5900 1350);
WIRE 16 -1 (5900 1450)(5650 1450);
WIRE 16 -1 (5900 1450)(5900 1400);
WIRE 16 -1 (5650 1500)(5900 1500);
WIRE 16 -1 (5900 1500)(5900 1450);
WIRE 16 -1 (5900 1550)(5900 1500);
WIRE 16 -1 (5650 1550)(5900 1550);
WIRE 16 -1 (5650 1600)(5900 1600);
WIRE 16 -1 (5900 1550)(5900 1600);
WIRE 16 -1 (5650 1650)(5900 1650);
WIRE 16 -1 (5900 1650)(5900 1600);
WIRE 16 -1 (5650 1700)(5900 1700);
WIRE 16 -1 (5900 1700)(5900 1650);
WIRE 16 -1 (5650 1750)(5900 1750);
WIRE 16 -1 (5900 1750)(5900 1700);
WIRE 16 -1 (5650 1800)(5900 1800);
WIRE 16 -1 (5900 1800)(5900 1750);
WIRE 16 -1 (5650 1850)(5900 1850);
WIRE 16 -1 (5900 1850)(5900 1800);
WIRE 16 -1 (5900 1900)(5650 1900);
WIRE 16 -1 (5900 1900)(5900 1850);
WIRE 16 -1 (5900 1950)(5650 1950);
WIRE 16 -1 (5900 1950)(5900 1900);
WIRE 16 -1 (5650 2000)(5900 2000);
WIRE 16 -1 (5900 2000)(5900 1950);
WIRE 16 -1 (5900 2050)(5900 2000);
WIRE 16 -1 (5650 2050)(5900 2050);
WIRE 16 -1 (5650 2100)(5900 2100);
WIRE 16 -1 (5900 2050)(5900 2100);
WIRE 16 -1 (5650 2150)(5900 2150);
WIRE 16 -1 (5900 2150)(5900 2100);
WIRE 16 -1 (5650 2200)(5900 2200);
WIRE 16 -1 (5900 2200)(5900 2150);
WIRE 16 -1 (5650 2250)(5900 2250);
WIRE 16 -1 (5900 2250)(5900 2200);
WIRE 16 -1 (5650 2300)(5900 2300);
WIRE 16 -1 (5900 2300)(5900 2250);
WIRE 16 -1 (5650 2350)(5900 2350);
WIRE 16 -1 (5900 2350)(5900 2300);
WIRE 16 -1 (5900 2400)(5650 2400);
WIRE 16 -1 (5900 2400)(5900 2350);
WIRE 16 -1 (5900 2450)(5650 2450);
WIRE 16 -1 (5900 2450)(5900 2400);
WIRE 16 -1 (5650 2500)(5900 2500);
WIRE 16 -1 (5900 2500)(5900 2450);
WIRE 16 -1 (5650 2550)(5900 2550);
WIRE 16 -1 (5900 2550)(5900 2500);
WIRE 16 -1 (5900 2550)(5900 2600);
WIRE 16 -1 (5650 2600)(5900 2600);
WIRE 16 -1 (5650 2650)(5900 2650);
WIRE 16 -1 (5900 2650)(5900 2600);
WIRE 16 -1 (5650 2700)(5900 2700);
WIRE 16 -1 (5900 2700)(5900 2650);
WIRE 16 -1 (5650 2750)(5900 2750);
WIRE 16 -1 (5900 2750)(5900 2700);
WIRE 16 -1 (5650 2800)(5900 2800);
WIRE 16 -1 (5900 2800)(5900 2750);
WIRE 16 -1 (5650 2850)(5900 2850);
WIRE 16 -1 (5900 2850)(5900 2800);
WIRE 16 -1 (5900 2900)(5650 2900);
WIRE 16 -1 (5900 2900)(5900 2850);
WIRE 16 -1 (5900 2950)(5650 2950);
WIRE 16 -1 (5900 2950)(5900 2900);
WIRE 16 -1 (5650 3000)(5900 3000);
WIRE 16 -1 (5900 3000)(5900 2950);
WIRE 16 -1 (5650 3050)(5900 3050);
WIRE 16 -1 (5900 3050)(5900 3000);
WIRE 16 -1 (5900 3050)(5900 3100);
WIRE 16 -1 (5650 3100)(5900 3100);
WIRE 16 -1 (5650 3150)(5900 3150);
WIRE 16 -1 (5900 3150)(5900 3100);
WIRE 16 -1 (5650 3200)(5900 3200);
WIRE 16 -1 (5900 3200)(5900 3150);
WIRE 16 -1 (5650 3250)(5900 3250);
WIRE 16 -1 (5900 3250)(5900 3200);
WIRE 16 -1 (5650 3300)(5900 3300);
WIRE 16 -1 (5900 3300)(5900 3250);
WIRE 16 -1 (5650 3350)(5900 3350);
WIRE 16 -1 (5900 3350)(5900 3300);
WIRE 16 -1 (5650 3400)(5900 3400);
WIRE 16 -1 (5900 3400)(5900 3350);
WIRE 16 -1 (5650 3450)(5900 3450);
WIRE 16 -1 (5900 3450)(5900 3400);
WIRE 16 -1 (5650 3500)(5900 3500);
WIRE 16 -1 (5900 3500)(5900 3450);
WIRE 16 -1 (5650 3550)(5900 3550);
WIRE 16 -1 (5900 3550)(5900 3500);
WIRE 16 -1 (5900 3600)(5900 3550);
WIRE 16 -1 (5650 3600)(5900 3600);
WIRE 16 -1 (5650 3650)(5900 3650);
WIRE 16 -1 (5900 3650)(5900 3600);
WIRE 16 -1 (5650 3700)(5900 3700);
WIRE 16 -1 (5900 3700)(5900 3650);
WIRE 16 -1 (5650 3750)(5900 3750);
WIRE 16 -1 (5900 3750)(5900 3700);
WIRE 16 -1 (5900 3800)(5900 3750);
WIRE 16 -1 (5650 3800)(5900 3800);
WIRE 16 -1 (-1650 2650)(-2750 2650);
FORCEPROP 2 LAST SIG_NAME M_A_CPU1_SB_CS_N<2>
J 0
(-2662 2659);
DISPLAY 0.680851 (-2662 2659);
PAINT WHITE (-2662 2659);
WIRE 16 -1 (-450 2650)(-275 2650);
WIRE 16 -1 (-450 1800)(-275 1800);
WIRE 16 -1 (-1650 550)(-2750 550);
FORCEPROP 2 LAST SIG_NAME TP_CHA_CPU1_DIMM2_FRU_0
J 0
(-2662 559);
DISPLAY 0.680851 (-2662 559);
PAINT WHITE (-2662 559);
WIRE 16 -1 (-1650 600)(-2750 600);
FORCEPROP 2 LAST SIG_NAME TP_CHA_CPU1_DIMM2_FRU_1
J 0
(-2662 609);
DISPLAY 0.680851 (-2662 609);
PAINT WHITE (-2662 609);
WIRE 16 -1 (-1650 650)(-2750 650);
FORCEPROP 2 LAST SIG_NAME TP_CHA_CPU1_DIMM2_FRU_2
J 0
(-2662 659);
DISPLAY 0.680851 (-2662 659);
PAINT WHITE (-2662 659);
WIRE 16 -1 (-1650 700)(-2750 700);
FORCEPROP 2 LAST SIG_NAME TP_CHA_CPU1_DIMM2_FRU_3
J 0
(-2662 709);
DISPLAY 0.680851 (-2662 709);
PAINT WHITE (-2662 709);
WIRE 16 -1 (-1650 750)(-2750 750);
FORCEPROP 2 LAST SIG_NAME TP_CHA_CPU1_DIMM2_FRU_4
J 0
(-2662 759);
DISPLAY 0.680851 (-2662 759);
PAINT WHITE (-2662 759);
WIRE 16 -1 (-1650 800)(-2750 800);
FORCEPROP 2 LAST SIG_NAME TP_CHA_CPU1_DIMM2_FRU_5
J 0
(-2662 809);
DISPLAY 0.680851 (-2662 809);
PAINT WHITE (-2662 809);
WIRE 16 -1 (-1650 850)(-2750 850);
FORCEPROP 2 LAST SIG_NAME TP_CHA_CPU1_DIMM2_FRU_6
J 0
(-2662 859);
DISPLAY 0.680851 (-2662 859);
PAINT WHITE (-2662 859);
WIRE 16 -1 (-1650 950)(-2750 950);
FORCEPROP 2 LAST SIG_NAME PWRGD_CHA_CPU1_DIMM2
J 0
(-2662 959);
DISPLAY 0.680851 (-2662 959);
PAINT WHITE (-2662 959);
WIRE 16 -1 (-1650 350)(-2750 350);
FORCEPROP 2 LAST SIG_NAME M_A_CPU1_SB_RSP<1>
J 0
(-2662 359);
DISPLAY 0.680851 (-2662 359);
PAINT WHITE (-2662 359);
WIRE 16 -1 (-1650 400)(-2750 400);
FORCEPROP 2 LAST SIG_NAME M_A_CPU1_SA_RSP<1>
J 0
(-2662 409);
DISPLAY 0.680851 (-2662 409);
PAINT WHITE (-2662 409);
WIRE 16 -1 (-450 600)(-275 600);
WIRE 16 -1 (-450 650)(-275 650);
WIRE 16 -1 (-450 700)(-275 700);
WIRE 16 -1 (-450 750)(-275 750);
WIRE 16 -1 (-450 800)(-275 800);
WIRE 16 -1 (-450 850)(-275 850);
WIRE 16 -1 (-450 900)(-275 900);
WIRE 16 -1 (-450 950)(-275 950);
WIRE 16 -1 (-450 1000)(-275 1000);
WIRE 16 -1 (-450 1050)(-275 1050);
WIRE 16 -1 (-450 1100)(-275 1100);
WIRE 16 -1 (-450 1150)(-275 1150);
WIRE 16 -1 (-450 1200)(-275 1200);
WIRE 16 -1 (-450 1250)(-275 1250);
WIRE 16 -1 (-450 1300)(-275 1300);
WIRE 16 -1 (-450 1350)(-275 1350);
WIRE 16 -1 (-450 1400)(-275 1400);
WIRE 16 -1 (-450 1450)(-275 1450);
WIRE 16 -1 (-450 1500)(-275 1500);
WIRE 16 -1 (-450 1550)(-275 1550);
WIRE 16 -1 (-450 1600)(-275 1600);
WIRE 16 -1 (-450 1650)(-275 1650);
WIRE 16 -1 (-450 1700)(-275 1700);
WIRE 16 -1 (-450 1750)(-275 1750);
WIRE 16 -1 (-450 1850)(-275 1850);
WIRE 16 -1 (-450 1900)(-275 1900);
WIRE 16 -1 (-450 2000)(-275 2000);
WIRE 16 -1 (-450 2050)(-275 2050);
WIRE 16 -1 (-450 2100)(-275 2100);
WIRE 16 -1 (-450 2150)(-275 2150);
WIRE 16 -1 (-450 2250)(-275 2250);
WIRE 16 -1 (-450 2300)(-275 2300);
WIRE 16 -1 (-450 2350)(-275 2350);
WIRE 16 -1 (-450 2400)(-275 2400);
WIRE 16 -1 (-450 2500)(-275 2500);
WIRE 16 -1 (-450 2550)(-275 2550);
WIRE 16 -1 (-450 2600)(-275 2600);
WIRE 16 -1 (-450 2700)(-275 2700);
WIRE 16 -1 (-450 2750)(-275 2750);
WIRE 16 -1 (-450 2800)(-275 2800);
WIRE 16 -1 (-450 2850)(-275 2850);
WIRE 16 -1 (-450 2900)(-275 2900);
WIRE 16 -1 (-450 2950)(-275 2950);
WIRE 16 -1 (-450 3000)(-275 3000);
WIRE 16 -1 (-450 3050)(-275 3050);
WIRE 16 -1 (-450 3100)(-275 3100);
WIRE 16 -1 (-450 3150)(-275 3150);
WIRE 16 -1 (-450 3200)(-275 3200);
WIRE 16 -1 (-450 3250)(-275 3250);
WIRE 16 -1 (-450 3300)(-275 3300);
WIRE 16 -1 (-450 3350)(-275 3350);
WIRE 16 -1 (-450 3400)(-275 3400);
WIRE 16 -1 (-450 3450)(-275 3450);
WIRE 16 -1 (-450 3500)(-275 3500);
WIRE 16 -1 (-450 3550)(-275 3550);
WIRE 16 -1 (-450 3600)(-275 3600);
WIRE 16 -1 (-450 3650)(-275 3650);
WIRE 16 -1 (-450 3700)(-275 3700);
WIRE 16 -1 (-450 3750)(-275 3750);
WIRE 16 -1 (-1650 2700)(-2750 2700);
FORCEPROP 2 LAST SIG_NAME M_A_CPU1_SB_CS_N<3>
J 0
(-2662 2709);
DISPLAY 0.680851 (-2662 2709);
PAINT WHITE (-2662 2709);
WIRE 16 -1 (-1650 2850)(-2750 2850);
FORCEPROP 2 LAST SIG_NAME M_A_CPU1_SA_CS_N<3>
J 0
(-2662 2859);
DISPLAY 0.680851 (-2662 2859);
PAINT WHITE (-2662 2859);
WIRE 16 -1 (-1650 2800)(-2750 2800);
FORCEPROP 2 LAST SIG_NAME M_A_CPU1_SA_CS_N<2>
J 0
(-2662 2809);
DISPLAY 0.680851 (-2662 2809);
PAINT WHITE (-2662 2809);
WIRE 16 -1 (-1650 2550)(-2750 2550);
FORCEPROP 2 LAST SIG_NAME M_A_CPU1_CLK_DP<1>
J 0
(-2662 2559);
DISPLAY 0.680851 (-2662 2559);
PAINT WHITE (-2662 2559);
WIRE 16 -1 (-1650 2500)(-2750 2500);
FORCEPROP 2 LAST SIG_NAME M_A_CPU1_CLK_DN<1>
J 0
(-2662 2509);
DISPLAY 0.680851 (-2662 2509);
PAINT WHITE (-2662 2509);
WIRE 16 -1 (-1825 1600)(-1650 1600);
WIRE 16 -1 (-1825 1700)(-1650 1700);
WIRE 16 -1 (-1825 1750)(-1650 1750);
WIRE 16 -1 (-1825 1800)(-1650 1800);
WIRE 16 -1 (-1825 1850)(-1650 1850);
WIRE 16 -1 (-1825 1900)(-1650 1900);
WIRE 16 -1 (-1825 2050)(-1650 2050);
WIRE 16 -1 (-1825 2150)(-1650 2150);
WIRE 16 -1 (-1825 2200)(-1650 2200);
WIRE 16 -1 (-1825 2300)(-1650 2300);
WIRE 16 -1 (-1825 2350)(-1650 2350);
WIRE 16 -1 (-1825 3400)(-1650 3400);
WIRE 16 -1 (-1825 3800)(-1650 3800);
WIRE 16 -1 (-1825 3350)(-1650 3350);
WIRE 16 -1 (-1825 3750)(-1650 3750);
WIRE 16 -1 (-1825 3300)(-1650 3300);
WIRE 16 -1 (-1825 3700)(-1650 3700);
WIRE 16 -1 (-1825 3250)(-1650 3250);
WIRE 16 -1 (-1825 3650)(-1650 3650);
WIRE 16 -1 (-1825 3200)(-1650 3200);
WIRE 16 -1 (-1825 3600)(-1650 3600);
WIRE 16 -1 (-1825 3150)(-1650 3150);
WIRE 16 -1 (-1825 3550)(-1650 3550);
WIRE 16 -1 (-1825 3100)(-1650 3100);
WIRE 16 -1 (-1825 3500)(-1650 3500);
WIRE 16 -1 (-1825 1950)(-1650 1950);
WIRE 16 -1 (-1825 2100)(-1650 2100);
WIRE 16 -1 (-1825 2250)(-1650 2250);
WIRE 16 -1 (-1825 2400)(-1650 2400);
WIRE 16 -1 (-450 3800)(-275 3800);
WIRE 16 -1 (-1650 -150)(-2750 -150);
FORCEPROP 2 LAST SIG_NAME PD_CHA_CPU1_DIMM2_SAA
J 0
(-2662 -141);
DISPLAY 0.680851 (-2662 -141);
PAINT WHITE (-2662 -141);
WIRE 16 -1 (-1650 -250)(-1650 -150);
WIRE 16 -1 (2500 150)(2500 25);
WIRE 16 -1 (3125 150)(2500 150);
WIRE 16 -1 (3125 25)(3125 150);
DOT 1 (4200 1650);
DOT 1 (4200 2350);
DOT 1 (4200 3150);
DOT 1 (5900 3750);
DOT 1 (5900 3700);
DOT 1 (5900 3650);
DOT 1 (5900 3600);
DOT 1 (5900 3550);
DOT 1 (5900 3500);
DOT 1 (5900 3450);
DOT 1 (5900 3350);
DOT 1 (5900 3400);
DOT 1 (5900 3300);
DOT 1 (5900 3250);
DOT 1 (5900 3200);
DOT 1 (5900 3150);
DOT 1 (5900 3100);
DOT 1 (5900 3050);
DOT 1 (5900 3000);
DOT 1 (5900 2950);
DOT 1 (5900 2850);
DOT 1 (5900 2900);
DOT 1 (5900 2700);
DOT 1 (5900 2800);
DOT 1 (5900 2750);
DOT 1 (5900 2650);
DOT 1 (5900 2600);
DOT 1 (5900 2550);
DOT 1 (5900 2450);
DOT 1 (5900 2500);
DOT 1 (5900 2400);
DOT 1 (5900 2350);
DOT 1 (5900 2300);
DOT 1 (5900 2250);
DOT 1 (5900 2200);
DOT 1 (5900 2150);
DOT 1 (5900 2100);
DOT 1 (4200 3750);
DOT 1 (4200 3800);
DOT 1 (4200 3600);
DOT 1 (4200 3500);
DOT 1 (4200 3550);
DOT 1 (4200 3450);
DOT 1 (4200 3400);
DOT 1 (4200 3350);
DOT 1 (4200 3300);
DOT 1 (4200 3250);
DOT 1 (4200 3200);
DOT 1 (4200 3100);
DOT 1 (4200 3050);
DOT 1 (4200 3000);
DOT 1 (4200 2950);
DOT 1 (4200 2900);
DOT 1 (4200 2850);
DOT 1 (4200 2800);
DOT 1 (4200 2750);
DOT 1 (4200 2700);
DOT 1 (4200 2600);
DOT 1 (4200 2650);
DOT 1 (4200 2550);
DOT 1 (4200 2500);
DOT 1 (4200 2450);
DOT 1 (4200 2400);
DOT 1 (4200 2300);
DOT 1 (4200 2250);
DOT 1 (4200 2200);
DOT 1 (4200 2150);
DOT 1 (4200 2100);
DOT 1 (5900 2050);
DOT 1 (4200 2050);
DOT 1 (5900 1950);
DOT 1 (5900 2000);
DOT 1 (5900 1900);
DOT 1 (5900 1850);
DOT 1 (5900 1800);
DOT 1 (5900 1750);
DOT 1 (5900 1700);
DOT 1 (5900 1650);
DOT 1 (5900 1600);
DOT 1 (5900 1550);
DOT 1 (5900 1500);
DOT 1 (5900 1450);
DOT 1 (5900 1400);
DOT 1 (5900 1300);
DOT 1 (5900 1350);
DOT 1 (5900 1250);
DOT 1 (5900 1150);
DOT 1 (5900 1200);
DOT 1 (5900 1050);
DOT 1 (5900 1100);
DOT 1 (5900 1000);
DOT 1 (5900 950);
DOT 1 (5900 900);
DOT 1 (5900 800);
DOT 1 (5900 850);
DOT 1 (5900 750);
DOT 1 (5900 700);
DOT 1 (5900 650);
DOT 1 (4200 1950);
DOT 1 (4200 2000);
DOT 1 (4200 1900);
DOT 1 (4200 1850);
DOT 1 (4200 1800);
DOT 1 (4200 1750);
DOT 1 (4200 1700);
DOT 1 (4200 1550);
DOT 1 (4200 1600);
DOT 1 (4200 1500);
DOT 1 (4200 1450);
DOT 1 (4200 1400);
DOT 1 (4200 1350);
DOT 1 (4200 1300);
DOT 1 (4200 1250);
DOT 1 (4200 1200);
DOT 1 (4200 1150);
DOT 1 (4200 1100);
DOT 1 (4200 1050);
DOT 1 (4200 1000);
DOT 1 (4200 950);
DOT 1 (4200 900);
DOT 1 (4200 850);
DOT 1 (4200 800);
DOT 1 (4200 750);
DOT 1 (4200 700);
DOT 1 (4200 650);
DOT 1 (4200 550);
DOT 1 (4200 600);
DOT 1 (2500 150);
DOT 1 (3125 -325);
DOT 1 (5900 550);
DOT 1 (5900 500);
DOT 1 (5900 450);
FORCENOTE
20210728 MODIFY FOR GT
(-3125 4475) 0;
DISPLAY LEFT (-3125 4475);
DISPLAY 2.510638 (-3125 4475);
PAINT PINK (-3125 4475);
QUIT
